(kicad_sch
	(version 20250114)
	(generator "eeschema")
	(generator_version "9.0")
	(paper "A3")
	(title_block
		(title "LPDDR4 Test Board")
		(date "2024-02-12")
		(rev "1.1.5")
	)
	(text "AVDDH decoupling"
		(exclude_from_sim no)
		(at 50.165 107.315 0)
		(effects
			(font
				(size 2.9972 2.9972)
				(thickness 0.5994)
				(bold yes)
			)
			(justify left bottom)
		)
	)
	(text "DVDDH decoupling"
		(exclude_from_sim no)
		(at 49.53 145.415 0)
		(effects
			(font
				(size 2.9972 2.9972)
				(thickness 0.5994)
				(bold yes)
			)
			(justify left bottom)
		)
	)
	(text "DVDDL decoupling"
		(exclude_from_sim no)
		(at 49.53 68.58 0)
		(effects
			(font
				(size 2.9972 2.9972)
				(thickness 0.5994)
				(bold yes)
			)
			(justify left bottom)
		)
	)
	(text "AVDDL_PLL decoupling"
		(exclude_from_sim no)
		(at 45.72 188.595 0)
		(effects
			(font
				(size 2.9972 2.9972)
				(thickness 0.5994)
				(bold yes)
			)
			(justify left bottom)
		)
	)
	(text "PHY"
		(exclude_from_sim no)
		(at 229.235 62.23 0)
		(effects
			(font
				(size 2.9972 2.9972)
				(thickness 0.5994)
				(bold yes)
			)
			(justify left bottom)
		)
	)
	(text "Pull down resistors"
		(exclude_from_sim no)
		(at 337.82 70.485 0)
		(effects
			(font
				(size 2.9972 2.9972)
				(thickness 0.5994)
				(bold yes)
			)
			(justify left bottom)
		)
	)
	(text "AVDDL decoupling"
		(exclude_from_sim no)
		(at 49.53 230.505 0)
		(effects
			(font
				(size 2.9972 2.9972)
				(thickness 0.5994)
				(bold yes)
			)
			(justify left bottom)
		)
	)
	(text "Pull up resistors"
		(exclude_from_sim no)
		(at 336.55 138.43 0)
		(effects
			(font
				(size 2.9972 2.9972)
				(thickness 0.5994)
				(bold yes)
			)
			(justify left bottom)
		)
	)
	(text "RJ45 Connector"
		(exclude_from_sim no)
		(at 247.65 196.85 0)
		(effects
			(font
				(size 2.9972 2.9972)
				(thickness 0.5994)
				(bold yes)
			)
			(justify right bottom)
		)
	)
	(junction
		(at 375.285 102.87)
		(diameter 0)
		(color 0 0 0 0)
	)
	(junction
		(at 71.12 80.01)
		(diameter 0)
		(color 0 0 0 0)
	)
	(junction
		(at 375.285 105.41)
		(diameter 0)
		(color 0 0 0 0)
	)
	(junction
		(at 258.445 130.81)
		(diameter 0)
		(color 0 0 0 0)
	)
	(junction
		(at 375.92 160.655)
		(diameter 0)
		(color 0 0 0 0)
	)
	(junction
		(at 57.15 80.01)
		(diameter 0)
		(color 0 0 0 0)
	)
	(junction
		(at 375.92 175.895)
		(diameter 0)
		(color 0 0 0 0)
	)
	(junction
		(at 160.655 97.79)
		(diameter 0)
		(color 0 0 0 0)
	)
	(junction
		(at 84.455 153.67)
		(diameter 0)
		(color 0 0 0 0)
	)
	(junction
		(at 72.39 243.84)
		(diameter 0)
		(color 0 0 0 0)
	)
	(junction
		(at 64.135 80.01)
		(diameter 0)
		(color 0 0 0 0)
	)
	(junction
		(at 77.47 153.67)
		(diameter 0)
		(color 0 0 0 0)
	)
	(junction
		(at 79.375 243.84)
		(diameter 0)
		(color 0 0 0 0)
	)
	(junction
		(at 375.92 155.575)
		(diameter 0)
		(color 0 0 0 0)
	)
	(junction
		(at 375.285 92.71)
		(diameter 0)
		(color 0 0 0 0)
	)
	(junction
		(at 178.435 107.95)
		(diameter 0)
		(color 0 0 0 0)
	)
	(junction
		(at 77.47 119.38)
		(diameter 0)
		(color 0 0 0 0)
	)
	(junction
		(at 375.92 153.035)
		(diameter 0)
		(color 0 0 0 0)
	)
	(junction
		(at 83.185 201.93)
		(diameter 0)
		(color 0 0 0 0)
	)
	(junction
		(at 375.285 90.17)
		(diameter 0)
		(color 0 0 0 0)
	)
	(junction
		(at 70.485 153.67)
		(diameter 0)
		(color 0 0 0 0)
	)
	(junction
		(at 43.18 80.01)
		(diameter 0)
		(color 0 0 0 0)
	)
	(junction
		(at 375.92 170.815)
		(diameter 0)
		(color 0 0 0 0)
	)
	(junction
		(at 375.285 100.33)
		(diameter 0)
		(color 0 0 0 0)
	)
	(junction
		(at 70.485 119.38)
		(diameter 0)
		(color 0 0 0 0)
	)
	(junction
		(at 56.515 153.67)
		(diameter 0)
		(color 0 0 0 0)
	)
	(junction
		(at 92.075 80.01)
		(diameter 0)
		(color 0 0 0 0)
	)
	(junction
		(at 78.105 80.01)
		(diameter 0)
		(color 0 0 0 0)
	)
	(junction
		(at 63.5 153.67)
		(diameter 0)
		(color 0 0 0 0)
	)
	(junction
		(at 50.165 80.01)
		(diameter 0)
		(color 0 0 0 0)
	)
	(junction
		(at 86.36 243.84)
		(diameter 0)
		(color 0 0 0 0)
	)
	(junction
		(at 160.655 107.95)
		(diameter 0)
		(color 0 0 0 0)
	)
	(junction
		(at 36.195 80.01)
		(diameter 0)
		(color 0 0 0 0)
	)
	(junction
		(at 375.285 87.63)
		(diameter 0)
		(color 0 0 0 0)
	)
	(junction
		(at 85.09 80.01)
		(diameter 0)
		(color 0 0 0 0)
	)
	(junction
		(at 375.92 168.275)
		(diameter 0)
		(color 0 0 0 0)
	)
	(junction
		(at 375.92 173.355)
		(diameter 0)
		(color 0 0 0 0)
	)
	(junction
		(at 375.92 163.195)
		(diameter 0)
		(color 0 0 0 0)
	)
	(junction
		(at 178.435 97.79)
		(diameter 0)
		(color 0 0 0 0)
	)
	(junction
		(at 375.285 95.25)
		(diameter 0)
		(color 0 0 0 0)
	)
	(junction
		(at 375.285 97.79)
		(diameter 0)
		(color 0 0 0 0)
	)
	(junction
		(at 76.2 201.93)
		(diameter 0)
		(color 0 0 0 0)
	)
	(junction
		(at 375.92 158.115)
		(diameter 0)
		(color 0 0 0 0)
	)
	(junction
		(at 63.5 119.38)
		(diameter 0)
		(color 0 0 0 0)
	)
	(junction
		(at 258.445 133.35)
		(diameter 0)
		(color 0 0 0 0)
	)
	(junction
		(at 375.92 165.735)
		(diameter 0)
		(color 0 0 0 0)
	)
	(junction
		(at 69.215 201.93)
		(diameter 0)
		(color 0 0 0 0)
	)
	(junction
		(at 65.405 243.84)
		(diameter 0)
		(color 0 0 0 0)
	)
	(no_connect
		(at 215.265 209.55)
	)
	(no_connect
		(at 255.905 82.55)
	)
	(wire
		(pts
			(xy 36.195 81.28) (xy 36.195 80.01)
		)
		(stroke
			(width 0)
			(type default)
		)
	)
	(wire
		(pts
			(xy 350.52 105.41) (xy 360.045 105.41)
		)
		(stroke
			(width 0)
			(type default)
		)
	)
	(wire
		(pts
			(xy 365.125 102.87) (xy 375.285 102.87)
		)
		(stroke
			(width 0)
			(type default)
		)
	)
	(wire
		(pts
			(xy 178.435 107.95) (xy 173.355 107.95)
		)
		(stroke
			(width 0)
			(type default)
		)
	)
	(wire
		(pts
			(xy 360.045 97.79) (xy 350.52 97.79)
		)
		(stroke
			(width 0)
			(type default)
		)
	)
	(wire
		(pts
			(xy 255.905 100.33) (xy 264.16 100.33)
		)
		(stroke
			(width 0)
			(type default)
		)
	)
	(wire
		(pts
			(xy 350.52 87.63) (xy 360.045 87.63)
		)
		(stroke
			(width 0)
			(type default)
		)
	)
	(wire
		(pts
			(xy 365.125 100.33) (xy 375.285 100.33)
		)
		(stroke
			(width 0)
			(type default)
		)
	)
	(wire
		(pts
			(xy 76.2 201.93) (xy 76.2 203.2)
		)
		(stroke
			(width 0)
			(type default)
		)
	)
	(wire
		(pts
			(xy 169.545 113.03) (xy 169.545 116.84)
		)
		(stroke
			(width 0)
			(type default)
		)
	)
	(wire
		(pts
			(xy 160.655 107.95) (xy 160.655 110.49)
		)
		(stroke
			(width 0)
			(type default)
		)
	)
	(wire
		(pts
			(xy 351.155 163.195) (xy 361.315 163.195)
		)
		(stroke
			(width 0)
			(type default)
		)
	)
	(wire
		(pts
			(xy 208.915 113.03) (xy 211.455 113.03)
		)
		(stroke
			(width 0)
			(type default)
		)
	)
	(wire
		(pts
			(xy 208.915 120.65) (xy 211.455 120.65)
		)
		(stroke
			(width 0)
			(type default)
		)
	)
	(wire
		(pts
			(xy 208.915 99.06) (xy 211.455 99.06)
		)
		(stroke
			(width 0)
			(type default)
		)
	)
	(wire
		(pts
			(xy 375.92 163.195) (xy 375.92 165.735)
		)
		(stroke
			(width 0)
			(type default)
		)
	)
	(wire
		(pts
			(xy 70.485 127) (xy 70.485 125.73)
		)
		(stroke
			(width 0)
			(type default)
		)
	)
	(wire
		(pts
			(xy 255.905 106.68) (xy 264.16 106.68)
		)
		(stroke
			(width 0)
			(type default)
		)
	)
	(wire
		(pts
			(xy 57.15 87.63) (xy 57.15 86.36)
		)
		(stroke
			(width 0)
			(type default)
		)
	)
	(wire
		(pts
			(xy 65.405 243.84) (xy 72.39 243.84)
		)
		(stroke
			(width 0)
			(type default)
		)
	)
	(wire
		(pts
			(xy 375.92 153.035) (xy 375.92 155.575)
		)
		(stroke
			(width 0)
			(type default)
		)
	)
	(wire
		(pts
			(xy 60.96 119.38) (xy 63.5 119.38)
		)
		(stroke
			(width 0)
			(type default)
		)
	)
	(wire
		(pts
			(xy 59.055 201.93) (xy 61.595 201.93)
		)
		(stroke
			(width 0)
			(type default)
		)
	)
	(wire
		(pts
			(xy 212.725 250.19) (xy 212.725 252.73)
		)
		(stroke
			(width 0)
			(type default)
		)
	)
	(wire
		(pts
			(xy 255.905 133.35) (xy 258.445 133.35)
		)
		(stroke
			(width 0)
			(type default)
		)
	)
	(wire
		(pts
			(xy 375.92 165.735) (xy 375.92 168.275)
		)
		(stroke
			(width 0)
			(type default)
		)
	)
	(wire
		(pts
			(xy 63.5 119.38) (xy 70.485 119.38)
		)
		(stroke
			(width 0)
			(type default)
		)
	)
	(wire
		(pts
			(xy 375.92 160.655) (xy 375.92 163.195)
		)
		(stroke
			(width 0)
			(type default)
		)
	)
	(wire
		(pts
			(xy 366.395 155.575) (xy 375.92 155.575)
		)
		(stroke
			(width 0)
			(type default)
		)
	)
	(wire
		(pts
			(xy 79.375 243.84) (xy 72.39 243.84)
		)
		(stroke
			(width 0)
			(type default)
		)
	)
	(wire
		(pts
			(xy 375.285 102.87) (xy 375.285 105.41)
		)
		(stroke
			(width 0)
			(type default)
		)
	)
	(wire
		(pts
			(xy 351.155 160.655) (xy 361.315 160.655)
		)
		(stroke
			(width 0)
			(type default)
		)
	)
	(wire
		(pts
			(xy 178.435 97.79) (xy 172.085 97.79)
		)
		(stroke
			(width 0)
			(type default)
		)
	)
	(wire
		(pts
			(xy 86.36 243.84) (xy 79.375 243.84)
		)
		(stroke
			(width 0)
			(type default)
		)
	)
	(wire
		(pts
			(xy 71.12 80.01) (xy 78.105 80.01)
		)
		(stroke
			(width 0)
			(type default)
		)
	)
	(wire
		(pts
			(xy 178.435 95.25) (xy 178.435 97.79)
		)
		(stroke
			(width 0)
			(type default)
		)
	)
	(wire
		(pts
			(xy 361.315 175.895) (xy 351.155 175.895)
		)
		(stroke
			(width 0)
			(type default)
		)
	)
	(wire
		(pts
			(xy 93.345 243.84) (xy 86.36 243.84)
		)
		(stroke
			(width 0)
			(type default)
		)
	)
	(wire
		(pts
			(xy 361.315 165.735) (xy 351.155 165.735)
		)
		(stroke
			(width 0)
			(type default)
		)
	)
	(wire
		(pts
			(xy 208.915 90.17) (xy 211.455 90.17)
		)
		(stroke
			(width 0)
			(type default)
		)
	)
	(wire
		(pts
			(xy 365.125 97.79) (xy 375.285 97.79)
		)
		(stroke
			(width 0)
			(type default)
		)
	)
	(wire
		(pts
			(xy 255.905 80.01) (xy 267.335 80.01)
		)
		(stroke
			(width 0)
			(type default)
		)
	)
	(wire
		(pts
			(xy 361.315 153.035) (xy 351.155 153.035)
		)
		(stroke
			(width 0)
			(type default)
		)
	)
	(wire
		(pts
			(xy 84.455 161.29) (xy 84.455 160.02)
		)
		(stroke
			(width 0)
			(type default)
		)
	)
	(wire
		(pts
			(xy 211.455 77.47) (xy 204.47 77.47)
		)
		(stroke
			(width 0)
			(type default)
		)
	)
	(wire
		(pts
			(xy 70.485 119.38) (xy 70.485 120.65)
		)
		(stroke
			(width 0)
			(type default)
		)
	)
	(wire
		(pts
			(xy 243.205 212.09) (xy 245.745 212.09)
		)
		(stroke
			(width 0)
			(type default)
		)
	)
	(wire
		(pts
			(xy 260.35 217.17) (xy 260.35 207.01)
		)
		(stroke
			(width 0)
			(type default)
		)
	)
	(wire
		(pts
			(xy 208.915 127) (xy 211.455 127)
		)
		(stroke
			(width 0)
			(type default)
		)
	)
	(wire
		(pts
			(xy 77.47 161.29) (xy 77.47 160.02)
		)
		(stroke
			(width 0)
			(type default)
		)
	)
	(wire
		(pts
			(xy 160.655 97.79) (xy 167.005 97.79)
		)
		(stroke
			(width 0)
			(type default)
		)
	)
	(wire
		(pts
			(xy 208.915 81.28) (xy 211.455 81.28)
		)
		(stroke
			(width 0)
			(type default)
		)
	)
	(wire
		(pts
			(xy 255.905 90.17) (xy 264.16 90.17)
		)
		(stroke
			(width 0)
			(type default)
		)
	)
	(wire
		(pts
			(xy 208.915 93.98) (xy 211.455 93.98)
		)
		(stroke
			(width 0)
			(type default)
		)
	)
	(wire
		(pts
			(xy 351.155 178.435) (xy 361.315 178.435)
		)
		(stroke
			(width 0)
			(type default)
		)
	)
	(wire
		(pts
			(xy 360.045 90.17) (xy 350.52 90.17)
		)
		(stroke
			(width 0)
			(type default)
		)
	)
	(wire
		(pts
			(xy 53.34 119.38) (xy 55.88 119.38)
		)
		(stroke
			(width 0)
			(type default)
		)
	)
	(wire
		(pts
			(xy 351.155 173.355) (xy 361.315 173.355)
		)
		(stroke
			(width 0)
			(type default)
		)
	)
	(wire
		(pts
			(xy 243.205 209.55) (xy 250.825 209.55)
		)
		(stroke
			(width 0)
			(type default)
		)
	)
	(wire
		(pts
			(xy 50.165 80.01) (xy 50.165 81.28)
		)
		(stroke
			(width 0)
			(type default)
		)
	)
	(wire
		(pts
			(xy 55.245 243.84) (xy 57.785 243.84)
		)
		(stroke
			(width 0)
			(type default)
		)
	)
	(wire
		(pts
			(xy 215.265 232.41) (xy 205.74 232.41)
		)
		(stroke
			(width 0)
			(type default)
		)
	)
	(wire
		(pts
			(xy 63.5 161.29) (xy 63.5 160.02)
		)
		(stroke
			(width 0)
			(type default)
		)
	)
	(wire
		(pts
			(xy 215.265 219.71) (xy 205.74 219.71)
		)
		(stroke
			(width 0)
			(type default)
		)
	)
	(wire
		(pts
			(xy 36.195 87.63) (xy 36.195 86.36)
		)
		(stroke
			(width 0)
			(type default)
		)
	)
	(wire
		(pts
			(xy 36.195 80.01) (xy 43.18 80.01)
		)
		(stroke
			(width 0)
			(type default)
		)
	)
	(wire
		(pts
			(xy 365.125 90.17) (xy 375.285 90.17)
		)
		(stroke
			(width 0)
			(type default)
		)
	)
	(wire
		(pts
			(xy 215.265 217.17) (xy 205.74 217.17)
		)
		(stroke
			(width 0)
			(type default)
		)
	)
	(wire
		(pts
			(xy 84.455 154.94) (xy 84.455 153.67)
		)
		(stroke
			(width 0)
			(type default)
		)
	)
	(wire
		(pts
			(xy 71.12 80.01) (xy 71.12 81.28)
		)
		(stroke
			(width 0)
			(type default)
		)
	)
	(wire
		(pts
			(xy 64.135 80.01) (xy 64.135 81.28)
		)
		(stroke
			(width 0)
			(type default)
		)
	)
	(wire
		(pts
			(xy 366.395 168.275) (xy 375.92 168.275)
		)
		(stroke
			(width 0)
			(type default)
		)
	)
	(wire
		(pts
			(xy 361.315 158.115) (xy 351.155 158.115)
		)
		(stroke
			(width 0)
			(type default)
		)
	)
	(wire
		(pts
			(xy 207.645 237.49) (xy 215.265 237.49)
		)
		(stroke
			(width 0)
			(type default)
		)
	)
	(wire
		(pts
			(xy 215.265 229.87) (xy 205.74 229.87)
		)
		(stroke
			(width 0)
			(type default)
		)
	)
	(wire
		(pts
			(xy 208.915 130.81) (xy 211.455 130.81)
		)
		(stroke
			(width 0)
			(type default)
		)
	)
	(wire
		(pts
			(xy 77.47 127) (xy 77.47 125.73)
		)
		(stroke
			(width 0)
			(type default)
		)
	)
	(wire
		(pts
			(xy 70.485 153.67) (xy 70.485 154.94)
		)
		(stroke
			(width 0)
			(type default)
		)
	)
	(wire
		(pts
			(xy 366.395 173.355) (xy 375.92 173.355)
		)
		(stroke
			(width 0)
			(type default)
		)
	)
	(wire
		(pts
			(xy 208.915 133.35) (xy 211.455 133.35)
		)
		(stroke
			(width 0)
			(type default)
		)
	)
	(wire
		(pts
			(xy 375.92 170.815) (xy 375.92 173.355)
		)
		(stroke
			(width 0)
			(type default)
		)
	)
	(wire
		(pts
			(xy 70.485 161.29) (xy 70.485 160.02)
		)
		(stroke
			(width 0)
			(type default)
		)
	)
	(wire
		(pts
			(xy 92.075 87.63) (xy 92.075 86.36)
		)
		(stroke
			(width 0)
			(type default)
		)
	)
	(wire
		(pts
			(xy 250.825 209.55) (xy 250.825 207.01)
		)
		(stroke
			(width 0)
			(type default)
		)
	)
	(wire
		(pts
			(xy 366.395 163.195) (xy 375.92 163.195)
		)
		(stroke
			(width 0)
			(type default)
		)
	)
	(wire
		(pts
			(xy 56.515 153.67) (xy 56.515 154.94)
		)
		(stroke
			(width 0)
			(type default)
		)
	)
	(wire
		(pts
			(xy 361.315 170.815) (xy 351.155 170.815)
		)
		(stroke
			(width 0)
			(type default)
		)
	)
	(wire
		(pts
			(xy 375.285 105.41) (xy 375.285 113.03)
		)
		(stroke
			(width 0)
			(type default)
		)
	)
	(wire
		(pts
			(xy 366.395 153.035) (xy 375.92 153.035)
		)
		(stroke
			(width 0)
			(type default)
		)
	)
	(wire
		(pts
			(xy 72.39 243.84) (xy 72.39 245.11)
		)
		(stroke
			(width 0)
			(type default)
		)
	)
	(wire
		(pts
			(xy 350.52 100.33) (xy 360.045 100.33)
		)
		(stroke
			(width 0)
			(type default)
		)
	)
	(wire
		(pts
			(xy 85.09 80.01) (xy 85.09 81.28)
		)
		(stroke
			(width 0)
			(type default)
		)
	)
	(wire
		(pts
			(xy 258.445 118.11) (xy 255.905 118.11)
		)
		(stroke
			(width 0)
			(type default)
		)
	)
	(wire
		(pts
			(xy 208.915 110.49) (xy 211.455 110.49)
		)
		(stroke
			(width 0)
			(type default)
		)
	)
	(wire
		(pts
			(xy 350.52 92.71) (xy 360.045 92.71)
		)
		(stroke
			(width 0)
			(type default)
		)
	)
	(wire
		(pts
			(xy 255.905 96.52) (xy 264.16 96.52)
		)
		(stroke
			(width 0)
			(type default)
		)
	)
	(wire
		(pts
			(xy 56.515 153.67) (xy 63.5 153.67)
		)
		(stroke
			(width 0)
			(type default)
		)
	)
	(wire
		(pts
			(xy 77.47 120.65) (xy 77.47 119.38)
		)
		(stroke
			(width 0)
			(type default)
		)
	)
	(wire
		(pts
			(xy 375.92 173.355) (xy 375.92 175.895)
		)
		(stroke
			(width 0)
			(type default)
		)
	)
	(wire
		(pts
			(xy 365.125 87.63) (xy 375.285 87.63)
		)
		(stroke
			(width 0)
			(type default)
		)
	)
	(wire
		(pts
			(xy 375.92 168.275) (xy 375.92 170.815)
		)
		(stroke
			(width 0)
			(type default)
		)
	)
	(wire
		(pts
			(xy 76.2 209.55) (xy 76.2 208.28)
		)
		(stroke
			(width 0)
			(type default)
		)
	)
	(wire
		(pts
			(xy 366.395 158.115) (xy 375.92 158.115)
		)
		(stroke
			(width 0)
			(type default)
		)
	)
	(wire
		(pts
			(xy 208.915 118.11) (xy 211.455 118.11)
		)
		(stroke
			(width 0)
			(type default)
		)
	)
	(wire
		(pts
			(xy 86.36 245.11) (xy 86.36 243.84)
		)
		(stroke
			(width 0)
			(type default)
		)
	)
	(wire
		(pts
			(xy 208.915 104.14) (xy 211.455 104.14)
		)
		(stroke
			(width 0)
			(type default)
		)
	)
	(wire
		(pts
			(xy 215.265 240.03) (xy 212.725 240.03)
		)
		(stroke
			(width 0)
			(type default)
		)
	)
	(wire
		(pts
			(xy 208.915 115.57) (xy 211.455 115.57)
		)
		(stroke
			(width 0)
			(type default)
		)
	)
	(wire
		(pts
			(xy 72.39 251.46) (xy 72.39 250.19)
		)
		(stroke
			(width 0)
			(type default)
		)
	)
	(wire
		(pts
			(xy 215.265 224.79) (xy 205.74 224.79)
		)
		(stroke
			(width 0)
			(type default)
		)
	)
	(wire
		(pts
			(xy 53.975 153.67) (xy 56.515 153.67)
		)
		(stroke
			(width 0)
			(type default)
		)
	)
	(wire
		(pts
			(xy 69.215 201.93) (xy 76.2 201.93)
		)
		(stroke
			(width 0)
			(type default)
		)
	)
	(wire
		(pts
			(xy 64.135 87.63) (xy 64.135 86.36)
		)
		(stroke
			(width 0)
			(type default)
		)
	)
	(wire
		(pts
			(xy 43.18 80.01) (xy 50.165 80.01)
		)
		(stroke
			(width 0)
			(type default)
		)
	)
	(wire
		(pts
			(xy 258.445 123.19) (xy 258.445 124.46)
		)
		(stroke
			(width 0)
			(type default)
		)
	)
	(wire
		(pts
			(xy 365.125 95.25) (xy 375.285 95.25)
		)
		(stroke
			(width 0)
			(type default)
		)
	)
	(wire
		(pts
			(xy 70.485 153.67) (xy 77.47 153.67)
		)
		(stroke
			(width 0)
			(type default)
		)
	)
	(wire
		(pts
			(xy 360.045 85.09) (xy 350.52 85.09)
		)
		(stroke
			(width 0)
			(type default)
		)
	)
	(wire
		(pts
			(xy 260.35 199.39) (xy 260.35 201.93)
		)
		(stroke
			(width 0)
			(type default)
		)
	)
	(wire
		(pts
			(xy 160.655 115.57) (xy 160.655 116.84)
		)
		(stroke
			(width 0)
			(type default)
		)
	)
	(wire
		(pts
			(xy 84.455 119.38) (xy 77.47 119.38)
		)
		(stroke
			(width 0)
			(type default)
		)
	)
	(wire
		(pts
			(xy 160.655 107.95) (xy 160.655 97.79)
		)
		(stroke
			(width 0)
			(type default)
		)
	)
	(wire
		(pts
			(xy 71.12 87.63) (xy 71.12 86.36)
		)
		(stroke
			(width 0)
			(type default)
		)
	)
	(wire
		(pts
			(xy 84.455 153.67) (xy 77.47 153.67)
		)
		(stroke
			(width 0)
			(type default)
		)
	)
	(wire
		(pts
			(xy 375.285 87.63) (xy 375.285 90.17)
		)
		(stroke
			(width 0)
			(type default)
		)
	)
	(wire
		(pts
			(xy 375.92 158.115) (xy 375.92 160.655)
		)
		(stroke
			(width 0)
			(type default)
		)
	)
	(wire
		(pts
			(xy 375.285 92.71) (xy 375.285 95.25)
		)
		(stroke
			(width 0)
			(type default)
		)
	)
	(wire
		(pts
			(xy 255.905 123.19) (xy 258.445 123.19)
		)
		(stroke
			(width 0)
			(type default)
		)
	)
	(wire
		(pts
			(xy 85.09 87.63) (xy 85.09 86.36)
		)
		(stroke
			(width 0)
			(type default)
		)
	)
	(wire
		(pts
			(xy 375.92 155.575) (xy 375.92 158.115)
		)
		(stroke
			(width 0)
			(type default)
		)
	)
	(wire
		(pts
			(xy 63.5 119.38) (xy 63.5 120.65)
		)
		(stroke
			(width 0)
			(type default)
		)
	)
	(wire
		(pts
			(xy 33.655 80.01) (xy 36.195 80.01)
		)
		(stroke
			(width 0)
			(type default)
		)
	)
	(wire
		(pts
			(xy 63.5 153.67) (xy 63.5 154.94)
		)
		(stroke
			(width 0)
			(type default)
		)
	)
	(wire
		(pts
			(xy 86.36 251.46) (xy 86.36 250.19)
		)
		(stroke
			(width 0)
			(type default)
		)
	)
	(wire
		(pts
			(xy 208.915 101.6) (xy 211.455 101.6)
		)
		(stroke
			(width 0)
			(type default)
		)
	)
	(wire
		(pts
			(xy 258.445 130.81) (xy 258.445 129.54)
		)
		(stroke
			(width 0)
			(type default)
		)
	)
	(wire
		(pts
			(xy 243.205 217.17) (xy 260.35 217.17)
		)
		(stroke
			(width 0)
			(type default)
		)
	)
	(wire
		(pts
			(xy 57.15 80.01) (xy 64.135 80.01)
		)
		(stroke
			(width 0)
			(type default)
		)
	)
	(wire
		(pts
			(xy 351.155 168.275) (xy 361.315 168.275)
		)
		(stroke
			(width 0)
			(type default)
		)
	)
	(wire
		(pts
			(xy 208.915 87.63) (xy 211.455 87.63)
		)
		(stroke
			(width 0)
			(type default)
		)
	)
	(wire
		(pts
			(xy 79.375 245.11) (xy 79.375 243.84)
		)
		(stroke
			(width 0)
			(type default)
		)
	)
	(wire
		(pts
			(xy 262.89 73.66) (xy 255.905 73.66)
		)
		(stroke
			(width 0)
			(type default)
		)
	)
	(wire
		(pts
			(xy 366.395 178.435) (xy 375.92 178.435)
		)
		(stroke
			(width 0)
			(type default)
		)
	)
	(wire
		(pts
			(xy 43.18 87.63) (xy 43.18 86.36)
		)
		(stroke
			(width 0)
			(type default)
		)
	)
	(wire
		(pts
			(xy 255.905 130.81) (xy 258.445 130.81)
		)
		(stroke
			(width 0)
			(type default)
		)
	)
	(wire
		(pts
			(xy 215.265 222.25) (xy 205.74 222.25)
		)
		(stroke
			(width 0)
			(type default)
		)
	)
	(wire
		(pts
			(xy 262.89 77.47) (xy 255.905 77.47)
		)
		(stroke
			(width 0)
			(type default)
		)
	)
	(wire
		(pts
			(xy 365.125 85.09) (xy 375.285 85.09)
		)
		(stroke
			(width 0)
			(type default)
		)
	)
	(wire
		(pts
			(xy 375.285 85.09) (xy 375.285 87.63)
		)
		(stroke
			(width 0)
			(type default)
		)
	)
	(wire
		(pts
			(xy 375.285 97.79) (xy 375.285 100.33)
		)
		(stroke
			(width 0)
			(type default)
		)
	)
	(wire
		(pts
			(xy 69.215 201.93) (xy 69.215 203.2)
		)
		(stroke
			(width 0)
			(type default)
		)
	)
	(wire
		(pts
			(xy 92.075 80.01) (xy 85.09 80.01)
		)
		(stroke
			(width 0)
			(type default)
		)
	)
	(wire
		(pts
			(xy 178.435 107.95) (xy 178.435 97.79)
		)
		(stroke
			(width 0)
			(type default)
		)
	)
	(wire
		(pts
			(xy 375.285 100.33) (xy 375.285 102.87)
		)
		(stroke
			(width 0)
			(type default)
		)
	)
	(wire
		(pts
			(xy 63.5 153.67) (xy 70.485 153.67)
		)
		(stroke
			(width 0)
			(type default)
		)
	)
	(wire
		(pts
			(xy 62.865 243.84) (xy 65.405 243.84)
		)
		(stroke
			(width 0)
			(type default)
		)
	)
	(wire
		(pts
			(xy 211.455 73.66) (xy 204.47 73.66)
		)
		(stroke
			(width 0)
			(type default)
		)
	)
	(wire
		(pts
			(xy 208.915 96.52) (xy 211.455 96.52)
		)
		(stroke
			(width 0)
			(type default)
		)
	)
	(wire
		(pts
			(xy 178.435 115.57) (xy 178.435 116.84)
		)
		(stroke
			(width 0)
			(type default)
		)
	)
	(wire
		(pts
			(xy 366.395 165.735) (xy 375.92 165.735)
		)
		(stroke
			(width 0)
			(type default)
		)
	)
	(wire
		(pts
			(xy 77.47 153.67) (xy 77.47 154.94)
		)
		(stroke
			(width 0)
			(type default)
		)
	)
	(wire
		(pts
			(xy 365.125 92.71) (xy 375.285 92.71)
		)
		(stroke
			(width 0)
			(type default)
		)
	)
	(wire
		(pts
			(xy 91.44 153.67) (xy 84.455 153.67)
		)
		(stroke
			(width 0)
			(type default)
		)
	)
	(wire
		(pts
			(xy 92.075 81.28) (xy 92.075 80.01)
		)
		(stroke
			(width 0)
			(type default)
		)
	)
	(wire
		(pts
			(xy 250.825 199.39) (xy 250.825 201.93)
		)
		(stroke
			(width 0)
			(type default)
		)
	)
	(wire
		(pts
			(xy 50.165 87.63) (xy 50.165 86.36)
		)
		(stroke
			(width 0)
			(type default)
		)
	)
	(wire
		(pts
			(xy 375.92 175.895) (xy 375.92 178.435)
		)
		(stroke
			(width 0)
			(type default)
		)
	)
	(wire
		(pts
			(xy 43.18 80.01) (xy 43.18 81.28)
		)
		(stroke
			(width 0)
			(type default)
		)
	)
	(wire
		(pts
			(xy 83.185 203.2) (xy 83.185 201.93)
		)
		(stroke
			(width 0)
			(type default)
		)
	)
	(wire
		(pts
			(xy 255.905 93.98) (xy 264.16 93.98)
		)
		(stroke
			(width 0)
			(type default)
		)
	)
	(wire
		(pts
			(xy 258.445 130.81) (xy 258.445 133.35)
		)
		(stroke
			(width 0)
			(type default)
		)
	)
	(wire
		(pts
			(xy 207.645 237.49) (xy 207.645 252.73)
		)
		(stroke
			(width 0)
			(type default)
		)
	)
	(wire
		(pts
			(xy 66.675 201.93) (xy 69.215 201.93)
		)
		(stroke
			(width 0)
			(type default)
		)
	)
	(wire
		(pts
			(xy 78.105 80.01) (xy 85.09 80.01)
		)
		(stroke
			(width 0)
			(type default)
		)
	)
	(wire
		(pts
			(xy 56.515 161.29) (xy 56.515 160.02)
		)
		(stroke
			(width 0)
			(type default)
		)
	)
	(wire
		(pts
			(xy 94.615 201.93) (xy 83.185 201.93)
		)
		(stroke
			(width 0)
			(type default)
		)
	)
	(wire
		(pts
			(xy 360.045 102.87) (xy 350.52 102.87)
		)
		(stroke
			(width 0)
			(type default)
		)
	)
	(wire
		(pts
			(xy 50.165 80.01) (xy 57.15 80.01)
		)
		(stroke
			(width 0)
			(type default)
		)
	)
	(wire
		(pts
			(xy 215.265 227.33) (xy 205.74 227.33)
		)
		(stroke
			(width 0)
			(type default)
		)
	)
	(wire
		(pts
			(xy 366.395 170.815) (xy 375.92 170.815)
		)
		(stroke
			(width 0)
			(type default)
		)
	)
	(wire
		(pts
			(xy 178.435 110.49) (xy 178.435 107.95)
		)
		(stroke
			(width 0)
			(type default)
		)
	)
	(wire
		(pts
			(xy 83.185 201.93) (xy 76.2 201.93)
		)
		(stroke
			(width 0)
			(type default)
		)
	)
	(wire
		(pts
			(xy 78.105 80.01) (xy 78.105 81.28)
		)
		(stroke
			(width 0)
			(type default)
		)
	)
	(wire
		(pts
			(xy 255.905 109.22) (xy 264.16 109.22)
		)
		(stroke
			(width 0)
			(type default)
		)
	)
	(wire
		(pts
			(xy 208.915 83.82) (xy 211.455 83.82)
		)
		(stroke
			(width 0)
			(type default)
		)
	)
	(wire
		(pts
			(xy 212.725 240.03) (xy 212.725 245.11)
		)
		(stroke
			(width 0)
			(type default)
		)
	)
	(wire
		(pts
			(xy 79.375 251.46) (xy 79.375 250.19)
		)
		(stroke
			(width 0)
			(type default)
		)
	)
	(wire
		(pts
			(xy 77.47 119.38) (xy 70.485 119.38)
		)
		(stroke
			(width 0)
			(type default)
		)
	)
	(wire
		(pts
			(xy 375.92 149.225) (xy 375.92 153.035)
		)
		(stroke
			(width 0)
			(type default)
		)
	)
	(wire
		(pts
			(xy 160.655 95.25) (xy 160.655 97.79)
		)
		(stroke
			(width 0)
			(type default)
		)
	)
	(wire
		(pts
			(xy 243.205 219.71) (xy 245.745 219.71)
		)
		(stroke
			(width 0)
			(type default)
		)
	)
	(wire
		(pts
			(xy 255.905 87.63) (xy 264.16 87.63)
		)
		(stroke
			(width 0)
			(type default)
		)
	)
	(wire
		(pts
			(xy 65.405 243.84) (xy 65.405 245.11)
		)
		(stroke
			(width 0)
			(type default)
		)
	)
	(wire
		(pts
			(xy 258.445 133.35) (xy 258.445 135.89)
		)
		(stroke
			(width 0)
			(type default)
		)
	)
	(wire
		(pts
			(xy 78.105 87.63) (xy 78.105 86.36)
		)
		(stroke
			(width 0)
			(type default)
		)
	)
	(wire
		(pts
			(xy 208.915 123.19) (xy 211.455 123.19)
		)
		(stroke
			(width 0)
			(type default)
		)
	)
	(wire
		(pts
			(xy 208.915 106.68) (xy 211.455 106.68)
		)
		(stroke
			(width 0)
			(type default)
		)
	)
	(wire
		(pts
			(xy 366.395 175.895) (xy 375.92 175.895)
		)
		(stroke
			(width 0)
			(type default)
		)
	)
	(wire
		(pts
			(xy 375.285 95.25) (xy 375.285 97.79)
		)
		(stroke
			(width 0)
			(type default)
		)
	)
	(wire
		(pts
			(xy 215.265 214.63) (xy 205.74 214.63)
		)
		(stroke
			(width 0)
			(type default)
		)
	)
	(wire
		(pts
			(xy 375.285 90.17) (xy 375.285 92.71)
		)
		(stroke
			(width 0)
			(type default)
		)
	)
	(wire
		(pts
			(xy 255.905 102.87) (xy 264.16 102.87)
		)
		(stroke
			(width 0)
			(type default)
		)
	)
	(wire
		(pts
			(xy 350.52 95.25) (xy 360.045 95.25)
		)
		(stroke
			(width 0)
			(type default)
		)
	)
	(wire
		(pts
			(xy 99.06 80.01) (xy 92.075 80.01)
		)
		(stroke
			(width 0)
			(type default)
		)
	)
	(wire
		(pts
			(xy 57.15 80.01) (xy 57.15 81.28)
		)
		(stroke
			(width 0)
			(type default)
		)
	)
	(wire
		(pts
			(xy 63.5 127) (xy 63.5 125.73)
		)
		(stroke
			(width 0)
			(type default)
		)
	)
	(wire
		(pts
			(xy 65.405 251.46) (xy 65.405 250.19)
		)
		(stroke
			(width 0)
			(type default)
		)
	)
	(wire
		(pts
			(xy 366.395 160.655) (xy 375.92 160.655)
		)
		(stroke
			(width 0)
			(type default)
		)
	)
	(wire
		(pts
			(xy 165.735 107.95) (xy 160.655 107.95)
		)
		(stroke
			(width 0)
			(type default)
		)
	)
	(wire
		(pts
			(xy 83.185 209.55) (xy 83.185 208.28)
		)
		(stroke
			(width 0)
			(type default)
		)
	)
	(wire
		(pts
			(xy 69.215 209.55) (xy 69.215 208.28)
		)
		(stroke
			(width 0)
			(type default)
		)
	)
	(wire
		(pts
			(xy 258.445 115.57) (xy 255.905 115.57)
		)
		(stroke
			(width 0)
			(type default)
		)
	)
	(wire
		(pts
			(xy 64.135 80.01) (xy 71.12 80.01)
		)
		(stroke
			(width 0)
			(type default)
		)
	)
	(wire
		(pts
			(xy 365.125 105.41) (xy 375.285 105.41)
		)
		(stroke
			(width 0)
			(type default)
		)
	)
	(wire
		(pts
			(xy 351.155 155.575) (xy 361.315 155.575)
		)
		(stroke
			(width 0)
			(type default)
		)
	)
	(label "ETH3_N"
		(at 205.74 227.33 0)
		(effects
			(font
				(size 1.27 1.27)
			)
			(justify left bottom)
		)
	)
	(label "AVDDL_PLL"
		(at 267.335 80.01 180)
		(effects
			(font
				(size 1.27 1.27)
			)
			(justify right bottom)
		)
	)
	(label "ETH2_P"
		(at 205.74 219.71 0)
		(effects
			(font
				(size 1.27 1.27)
			)
			(justify left bottom)
		)
	)
	(label "AVDDL"
		(at 262.89 77.47 180)
		(effects
			(font
				(size 1.27 1.27)
			)
			(justify right bottom)
		)
	)
	(label "ETH2_N"
		(at 264.16 96.52 180)
		(effects
			(font
				(size 1.27 1.27)
			)
			(justify right bottom)
		)
	)
	(label "ETH2_N"
		(at 205.74 222.25 0)
		(effects
			(font
				(size 1.27 1.27)
			)
			(justify left bottom)
		)
	)
	(label "ETH4_P"
		(at 264.16 106.68 180)
		(effects
			(font
				(size 1.27 1.27)
			)
			(justify right bottom)
		)
	)
	(label "AVDDH"
		(at 204.47 77.47 0)
		(effects
			(font
				(size 1.27 1.27)
			)
			(justify left bottom)
		)
	)
	(label "DVDDH"
		(at 204.47 73.66 0)
		(effects
			(font
				(size 1.27 1.27)
			)
			(justify left bottom)
		)
	)
	(label "ETH1_N"
		(at 205.74 217.17 0)
		(effects
			(font
				(size 1.27 1.27)
			)
			(justify left bottom)
		)
	)
	(label "ETH4_N"
		(at 205.74 232.41 0)
		(effects
			(font
				(size 1.27 1.27)
			)
			(justify left bottom)
		)
	)
	(label "AVDDL"
		(at 93.345 243.84 180)
		(effects
			(font
				(size 1.27 1.27)
			)
			(justify right bottom)
		)
	)
	(label "ETH3_P"
		(at 264.16 100.33 180)
		(effects
			(font
				(size 1.27 1.27)
			)
			(justify right bottom)
		)
	)
	(label "DVDDL"
		(at 262.89 73.66 180)
		(effects
			(font
				(size 1.27 1.27)
			)
			(justify right bottom)
		)
	)
	(label "DVDDL"
		(at 99.06 80.01 180)
		(effects
			(font
				(size 1.27 1.27)
			)
			(justify right bottom)
		)
	)
	(label "ETH1_P"
		(at 264.16 87.63 180)
		(effects
			(font
				(size 1.27 1.27)
			)
			(justify right bottom)
		)
	)
	(label "ETH2_P"
		(at 264.16 93.98 180)
		(effects
			(font
				(size 1.27 1.27)
			)
			(justify right bottom)
		)
	)
	(label "ETH3_P"
		(at 205.74 224.79 0)
		(effects
			(font
				(size 1.27 1.27)
			)
			(justify left bottom)
		)
	)
	(label "AVDDH"
		(at 84.455 119.38 180)
		(effects
			(font
				(size 1.27 1.27)
			)
			(justify right bottom)
		)
	)
	(label "ETH1_P"
		(at 205.74 214.63 0)
		(effects
			(font
				(size 1.27 1.27)
			)
			(justify left bottom)
		)
	)
	(label "DVDDH"
		(at 91.44 153.67 180)
		(effects
			(font
				(size 1.27 1.27)
			)
			(justify right bottom)
		)
	)
	(label "AVDDL_PLL"
		(at 94.615 201.93 180)
		(effects
			(font
				(size 1.27 1.27)
			)
			(justify right bottom)
		)
	)
	(label "ETH3_N"
		(at 264.16 102.87 180)
		(effects
			(font
				(size 1.27 1.27)
			)
			(justify right bottom)
		)
	)
	(label "ETH4_P"
		(at 205.74 229.87 0)
		(effects
			(font
				(size 1.27 1.27)
			)
			(justify left bottom)
		)
	)
	(label "ETH1_N"
		(at 264.16 90.17 180)
		(effects
			(font
				(size 1.27 1.27)
			)
			(justify right bottom)
		)
	)
	(label "ETH4_N"
		(at 264.16 109.22 180)
		(effects
			(font
				(size 1.27 1.27)
			)
			(justify right bottom)
		)
	)
	(global_label "ETH_RXD1"
		(shape input)
		(at 208.915 115.57 180)
		(fields_autoplaced yes)
		(effects
			(font
				(size 1.27 1.27)
			)
			(justify right)
		)
		(property "Intersheetrefs" "${INTERSHEET_REFS}"
			(at -13.97 10.16 0)
			(effects
				(font
					(size 1.27 1.27)
				)
				(hide yes)
			)
		)
	)
	(global_label "ETH_XI"
		(shape input)
		(at 208.915 130.81 180)
		(fields_autoplaced yes)
		(effects
			(font
				(size 1.27 1.27)
			)
			(justify right)
		)
		(property "Intersheetrefs" "${INTERSHEET_REFS}"
			(at 200.3618 130.7306 0)
			(effects
				(font
					(size 1.27 1.27)
				)
				(justify right)
				(hide yes)
			)
		)
	)
	(global_label "ETH_TXD2"
		(shape input)
		(at 208.915 101.6 180)
		(fields_autoplaced yes)
		(effects
			(font
				(size 1.27 1.27)
			)
			(justify right)
		)
		(property "Intersheetrefs" "${INTERSHEET_REFS}"
			(at -13.97 11.43 0)
			(effects
				(font
					(size 1.27 1.27)
				)
				(hide yes)
			)
		)
	)
	(global_label "ETH_RX_DV"
		(shape input)
		(at 351.155 163.195 180)
		(fields_autoplaced yes)
		(effects
			(font
				(size 1.27 1.27)
			)
			(justify right)
		)
		(property "Intersheetrefs" "${INTERSHEET_REFS}"
			(at 24.13 108.585 0)
			(effects
				(font
					(size 1.27 1.27)
				)
				(hide yes)
			)
		)
	)
	(global_label "ETH_XO"
		(shape input)
		(at 160.655 95.25 90)
		(fields_autoplaced yes)
		(effects
			(font
				(size 1.27 1.27)
			)
			(justify left)
		)
		(property "Intersheetrefs" "${INTERSHEET_REFS}"
			(at 160.7344 85.971 90)
			(effects
				(font
					(size 1.27 1.27)
				)
				(justify left)
				(hide yes)
			)
		)
	)
	(global_label "LED_LINK"
		(shape input)
		(at 245.745 212.09 0)
		(fields_autoplaced yes)
		(effects
			(font
				(size 1.27 1.27)
			)
			(justify left)
		)
		(property "Intersheetrefs" "${INTERSHEET_REFS}"
			(at -41.275 5.715 0)
			(effects
				(font
					(size 1.27 1.27)
				)
				(hide yes)
			)
		)
	)
	(global_label "ETH_MDIO"
		(shape input)
		(at 351.155 175.895 180)
		(fields_autoplaced yes)
		(effects
			(font
				(size 1.27 1.27)
			)
			(justify right)
		)
		(property "Intersheetrefs" "${INTERSHEET_REFS}"
			(at 24.13 108.585 0)
			(effects
				(font
					(size 1.27 1.27)
				)
				(hide yes)
			)
		)
	)
	(global_label "3V3_SYS"
		(shape input)
		(at 53.975 153.67 180)
		(fields_autoplaced yes)
		(effects
			(font
				(size 1.27 1.27)
			)
			(justify right)
		)
		(property "Intersheetrefs" "${INTERSHEET_REFS}"
			(at 8.255 -6.35 0)
			(effects
				(font
					(size 1.27 1.27)
				)
				(hide yes)
			)
		)
	)
	(global_label "LED_LINK"
		(shape input)
		(at 351.155 173.355 180)
		(fields_autoplaced yes)
		(effects
			(font
				(size 1.27 1.27)
			)
			(justify right)
		)
		(property "Intersheetrefs" "${INTERSHEET_REFS}"
			(at 24.13 108.585 0)
			(effects
				(font
					(size 1.27 1.27)
				)
				(hide yes)
			)
		)
	)
	(global_label "ETH_RXD2"
		(shape input)
		(at 351.155 158.115 180)
		(fields_autoplaced yes)
		(effects
			(font
				(size 1.27 1.27)
			)
			(justify right)
		)
		(property "Intersheetrefs" "${INTERSHEET_REFS}"
			(at 24.13 108.585 0)
			(effects
				(font
					(size 1.27 1.27)
				)
				(hide yes)
			)
		)
	)
	(global_label "ETH_XI"
		(shape input)
		(at 178.435 95.25 90)
		(fields_autoplaced yes)
		(effects
			(font
				(size 1.27 1.27)
			)
			(justify left)
		)
		(property "Intersheetrefs" "${INTERSHEET_REFS}"
			(at 178.5144 86.6968 90)
			(effects
				(font
					(size 1.27 1.27)
				)
				(justify left)
				(hide yes)
			)
		)
	)
	(global_label "ETH_RXD0"
		(shape input)
		(at 351.155 153.035 180)
		(fields_autoplaced yes)
		(effects
			(font
				(size 1.27 1.27)
			)
			(justify right)
		)
		(property "Intersheetrefs" "${INTERSHEET_REFS}"
			(at 24.13 108.585 0)
			(effects
				(font
					(size 1.27 1.27)
				)
				(hide yes)
			)
		)
	)
	(global_label "ETH_RX_CLK"
		(shape input)
		(at 208.915 123.19 180)
		(fields_autoplaced yes)
		(effects
			(font
				(size 1.27 1.27)
			)
			(justify right)
		)
		(property "Intersheetrefs" "${INTERSHEET_REFS}"
			(at -13.97 10.16 0)
			(effects
				(font
					(size 1.27 1.27)
				)
				(hide yes)
			)
		)
	)
	(global_label "ETH_MDIO"
		(shape input)
		(at 208.915 90.17 180)
		(fields_autoplaced yes)
		(effects
			(font
				(size 1.27 1.27)
			)
			(justify right)
		)
		(property "Intersheetrefs" "${INTERSHEET_REFS}"
			(at -13.97 12.7 0)
			(effects
				(font
					(size 1.27 1.27)
				)
				(hide yes)
			)
		)
	)
	(global_label "ETH_TX_CLK"
		(shape input)
		(at 208.915 106.68 180)
		(fields_autoplaced yes)
		(effects
			(font
				(size 1.27 1.27)
			)
			(justify right)
		)
		(property "Intersheetrefs" "${INTERSHEET_REFS}"
			(at -13.97 11.43 0)
			(effects
				(font
					(size 1.27 1.27)
				)
				(hide yes)
			)
		)
	)
	(global_label "ETH_XO"
		(shape input)
		(at 208.915 133.35 180)
		(fields_autoplaced yes)
		(effects
			(font
				(size 1.27 1.27)
			)
			(justify right)
		)
		(property "Intersheetrefs" "${INTERSHEET_REFS}"
			(at 199.636 133.2706 0)
			(effects
				(font
					(size 1.27 1.27)
				)
				(justify right)
				(hide yes)
			)
		)
	)
	(global_label "ETH_TXD3"
		(shape input)
		(at 208.915 104.14 180)
		(fields_autoplaced yes)
		(effects
			(font
				(size 1.27 1.27)
			)
			(justify right)
		)
		(property "Intersheetrefs" "${INTERSHEET_REFS}"
			(at -13.97 11.43 0)
			(effects
				(font
					(size 1.27 1.27)
				)
				(hide yes)
			)
		)
	)
	(global_label "1V2_SYS"
		(shape input)
		(at 33.655 80.01 180)
		(fields_autoplaced yes)
		(effects
			(font
				(size 1.27 1.27)
			)
			(justify right)
		)
		(property "Intersheetrefs" "${INTERSHEET_REFS}"
			(at 23.3479 79.9306 0)
			(effects
				(font
					(size 1.27 1.27)
				)
				(justify right)
				(hide yes)
			)
		)
	)
	(global_label "1V2_SYS"
		(shape input)
		(at 55.245 243.84 180)
		(fields_autoplaced yes)
		(effects
			(font
				(size 1.27 1.27)
			)
			(justify right)
		)
		(property "Intersheetrefs" "${INTERSHEET_REFS}"
			(at 44.9379 243.7606 0)
			(effects
				(font
					(size 1.27 1.27)
				)
				(justify right)
				(hide yes)
			)
		)
	)
	(global_label "LED_SPD"
		(shape input)
		(at 350.52 102.87 180)
		(fields_autoplaced yes)
		(effects
			(font
				(size 1.27 1.27)
			)
			(justify right)
		)
		(property "Intersheetrefs" "${INTERSHEET_REFS}"
			(at -22.225 40.64 0)
			(effects
				(font
					(size 1.27 1.27)
				)
				(hide yes)
			)
		)
	)
	(global_label "ETH_RXD2"
		(shape input)
		(at 208.915 118.11 180)
		(fields_autoplaced yes)
		(effects
			(font
				(size 1.27 1.27)
			)
			(justify right)
		)
		(property "Intersheetrefs" "${INTERSHEET_REFS}"
			(at -13.97 10.16 0)
			(effects
				(font
					(size 1.27 1.27)
				)
				(hide yes)
			)
		)
	)
	(global_label "LED_SPD"
		(shape input)
		(at 245.745 219.71 0)
		(fields_autoplaced yes)
		(effects
			(font
				(size 1.27 1.27)
			)
			(justify left)
		)
		(property "Intersheetrefs" "${INTERSHEET_REFS}"
			(at -41.275 8.255 0)
			(effects
				(font
					(size 1.27 1.27)
				)
				(hide yes)
			)
		)
	)
	(global_label "1V2_SYS"
		(shape input)
		(at 59.055 201.93 180)
		(fields_autoplaced yes)
		(effects
			(font
				(size 1.27 1.27)
			)
			(justify right)
		)
		(property "Intersheetrefs" "${INTERSHEET_REFS}"
			(at 48.7479 202.0094 0)
			(effects
				(font
					(size 1.27 1.27)
				)
				(justify right)
				(hide yes)
			)
		)
	)
	(global_label "ETH_RX_CLK"
		(shape input)
		(at 350.52 97.79 180)
		(fields_autoplaced yes)
		(effects
			(font
				(size 1.27 1.27)
			)
			(justify right)
		)
		(property "Intersheetrefs" "${INTERSHEET_REFS}"
			(at -22.225 40.64 0)
			(effects
				(font
					(size 1.27 1.27)
				)
				(hide yes)
			)
		)
	)
	(global_label "ETH_TXD0"
		(shape input)
		(at 208.915 96.52 180)
		(fields_autoplaced yes)
		(effects
			(font
				(size 1.27 1.27)
			)
			(justify right)
		)
		(property "Intersheetrefs" "${INTERSHEET_REFS}"
			(at -13.97 11.43 0)
			(effects
				(font
					(size 1.27 1.27)
				)
				(hide yes)
			)
		)
	)
	(global_label "ETH_RSTN"
		(shape input)
		(at 208.915 81.28 180)
		(fields_autoplaced yes)
		(effects
			(font
				(size 1.27 1.27)
			)
			(justify right)
		)
		(property "Intersheetrefs" "${INTERSHEET_REFS}"
			(at -13.335 -49.53 0)
			(effects
				(font
					(size 1.27 1.27)
				)
				(hide yes)
			)
		)
	)
	(global_label "ETH_REF_CLK"
		(shape input)
		(at 350.52 100.33 180)
		(fields_autoplaced yes)
		(effects
			(font
				(size 1.27 1.27)
			)
			(justify right)
		)
		(property "Intersheetrefs" "${INTERSHEET_REFS}"
			(at -22.225 40.64 0)
			(effects
				(font
					(size 1.27 1.27)
				)
				(hide yes)
			)
		)
	)
	(global_label "ETH_RXD3"
		(shape input)
		(at 208.915 120.65 180)
		(fields_autoplaced yes)
		(effects
			(font
				(size 1.27 1.27)
			)
			(justify right)
		)
		(property "Intersheetrefs" "${INTERSHEET_REFS}"
			(at -13.97 10.16 0)
			(effects
				(font
					(size 1.27 1.27)
				)
				(hide yes)
			)
		)
	)
	(global_label "3V3_SYS"
		(shape input)
		(at 53.34 119.38 180)
		(fields_autoplaced yes)
		(effects
			(font
				(size 1.27 1.27)
			)
			(justify right)
		)
		(property "Intersheetrefs" "${INTERSHEET_REFS}"
			(at 5.715 2.54 0)
			(effects
				(font
					(size 1.27 1.27)
				)
				(hide yes)
			)
		)
	)
	(global_label "ETH_RXD0"
		(shape input)
		(at 208.915 113.03 180)
		(fields_autoplaced yes)
		(effects
			(font
				(size 1.27 1.27)
			)
			(justify right)
		)
		(property "Intersheetrefs" "${INTERSHEET_REFS}"
			(at -13.97 10.16 0)
			(effects
				(font
					(size 1.27 1.27)
				)
				(hide yes)
			)
		)
	)
	(global_label "ETH_RXD3"
		(shape input)
		(at 350.52 92.71 180)
		(fields_autoplaced yes)
		(effects
			(font
				(size 1.27 1.27)
			)
			(justify right)
		)
		(property "Intersheetrefs" "${INTERSHEET_REFS}"
			(at -22.225 40.64 0)
			(effects
				(font
					(size 1.27 1.27)
				)
				(hide yes)
			)
		)
	)
	(global_label "ETH_TX_EN"
		(shape input)
		(at 208.915 93.98 180)
		(fields_autoplaced yes)
		(effects
			(font
				(size 1.27 1.27)
			)
			(justify right)
		)
		(property "Intersheetrefs" "${INTERSHEET_REFS}"
			(at -13.97 11.43 0)
			(effects
				(font
					(size 1.27 1.27)
				)
				(hide yes)
			)
		)
	)
	(global_label "ETH_RXD0"
		(shape input)
		(at 350.52 85.09 180)
		(fields_autoplaced yes)
		(effects
			(font
				(size 1.27 1.27)
			)
			(justify right)
		)
		(property "Intersheetrefs" "${INTERSHEET_REFS}"
			(at -22.225 40.64 0)
			(effects
				(font
					(size 1.27 1.27)
				)
				(hide yes)
			)
		)
	)
	(global_label "ETH_MDC"
		(shape input)
		(at 208.915 87.63 180)
		(fields_autoplaced yes)
		(effects
			(font
				(size 1.27 1.27)
			)
			(justify right)
		)
		(property "Intersheetrefs" "${INTERSHEET_REFS}"
			(at -13.97 12.7 0)
			(effects
				(font
					(size 1.27 1.27)
				)
				(hide yes)
			)
		)
	)
	(global_label "3V3_SYS"
		(shape input)
		(at 250.825 199.39 90)
		(fields_autoplaced yes)
		(effects
			(font
				(size 1.27 1.27)
			)
			(justify left)
		)
		(property "Intersheetrefs" "${INTERSHEET_REFS}"
			(at -22.225 7.62 0)
			(effects
				(font
					(size 1.27 1.27)
				)
				(hide yes)
			)
		)
	)
	(global_label "3V3_SYS"
		(shape input)
		(at 375.92 149.225 90)
		(fields_autoplaced yes)
		(effects
			(font
				(size 1.27 1.27)
			)
			(justify left)
		)
		(property "Intersheetrefs" "${INTERSHEET_REFS}"
			(at 24.13 108.585 0)
			(effects
				(font
					(size 1.27 1.27)
				)
				(hide yes)
			)
		)
	)
	(global_label "ETH_RXD3"
		(shape input)
		(at 351.155 160.655 180)
		(fields_autoplaced yes)
		(effects
			(font
				(size 1.27 1.27)
			)
			(justify right)
		)
		(property "Intersheetrefs" "${INTERSHEET_REFS}"
			(at 24.13 108.585 0)
			(effects
				(font
					(size 1.27 1.27)
				)
				(hide yes)
			)
		)
	)
	(global_label "LED_SPD"
		(shape input)
		(at 351.155 170.815 180)
		(fields_autoplaced yes)
		(effects
			(font
				(size 1.27 1.27)
			)
			(justify right)
		)
		(property "Intersheetrefs" "${INTERSHEET_REFS}"
			(at 24.13 108.585 0)
			(effects
				(font
					(size 1.27 1.27)
				)
				(hide yes)
			)
		)
	)
	(global_label "3V3_SYS"
		(shape input)
		(at 260.35 199.39 90)
		(fields_autoplaced yes)
		(effects
			(font
				(size 1.27 1.27)
			)
			(justify left)
		)
		(property "Intersheetrefs" "${INTERSHEET_REFS}"
			(at -19.685 7.62 0)
			(effects
				(font
					(size 1.27 1.27)
				)
				(hide yes)
			)
		)
	)
	(global_label "ETH_TXD1"
		(shape input)
		(at 208.915 99.06 180)
		(fields_autoplaced yes)
		(effects
			(font
				(size 1.27 1.27)
			)
			(justify right)
		)
		(property "Intersheetrefs" "${INTERSHEET_REFS}"
			(at -13.97 11.43 0)
			(effects
				(font
					(size 1.27 1.27)
				)
				(hide yes)
			)
		)
	)
	(global_label "ETH_RX_DV"
		(shape input)
		(at 208.915 110.49 180)
		(fields_autoplaced yes)
		(effects
			(font
				(size 1.27 1.27)
			)
			(justify right)
		)
		(property "Intersheetrefs" "${INTERSHEET_REFS}"
			(at -13.97 10.16 0)
			(effects
				(font
					(size 1.27 1.27)
				)
				(hide yes)
			)
		)
	)
	(global_label "ETH_REF_CLK"
		(shape input)
		(at 208.915 127 180)
		(fields_autoplaced yes)
		(effects
			(font
				(size 1.27 1.27)
			)
			(justify right)
		)
		(property "Intersheetrefs" "${INTERSHEET_REFS}"
			(at -13.335 -1.27 0)
			(effects
				(font
					(size 1.27 1.27)
				)
				(hide yes)
			)
		)
	)
	(global_label "LED_LINK"
		(shape input)
		(at 258.445 115.57 0)
		(fields_autoplaced yes)
		(effects
			(font
				(size 1.27 1.27)
			)
			(justify left)
		)
		(property "Intersheetrefs" "${INTERSHEET_REFS}"
			(at 481.33 236.22 0)
			(effects
				(font
					(size 1.27 1.27)
				)
				(hide yes)
			)
		)
	)
	(global_label "ETH_RXD1"
		(shape input)
		(at 350.52 87.63 180)
		(fields_autoplaced yes)
		(effects
			(font
				(size 1.27 1.27)
			)
			(justify right)
		)
		(property "Intersheetrefs" "${INTERSHEET_REFS}"
			(at -22.225 40.64 0)
			(effects
				(font
					(size 1.27 1.27)
				)
				(hide yes)
			)
		)
	)
	(global_label "ETH_RXD1"
		(shape input)
		(at 351.155 155.575 180)
		(fields_autoplaced yes)
		(effects
			(font
				(size 1.27 1.27)
			)
			(justify right)
		)
		(property "Intersheetrefs" "${INTERSHEET_REFS}"
			(at 24.13 108.585 0)
			(effects
				(font
					(size 1.27 1.27)
				)
				(hide yes)
			)
		)
	)
	(global_label "ETH_RSTN"
		(shape input)
		(at 351.155 178.435 180)
		(fields_autoplaced yes)
		(effects
			(font
				(size 1.27 1.27)
			)
			(justify right)
		)
		(property "Intersheetrefs" "${INTERSHEET_REFS}"
			(at 24.13 108.585 0)
			(effects
				(font
					(size 1.27 1.27)
				)
				(hide yes)
			)
		)
	)
	(global_label "LED_LINK"
		(shape input)
		(at 350.52 105.41 180)
		(fields_autoplaced yes)
		(effects
			(font
				(size 1.27 1.27)
			)
			(justify right)
		)
		(property "Intersheetrefs" "${INTERSHEET_REFS}"
			(at -22.225 40.64 0)
			(effects
				(font
					(size 1.27 1.27)
				)
				(hide yes)
			)
		)
	)
	(global_label "ETH_INT_N"
		(shape input)
		(at 208.915 83.82 180)
		(fields_autoplaced yes)
		(effects
			(font
				(size 1.27 1.27)
			)
			(justify right)
		)
		(property "Intersheetrefs" "${INTERSHEET_REFS}"
			(at 196.9751 83.7406 0)
			(effects
				(font
					(size 1.27 1.27)
				)
				(justify right)
				(hide yes)
			)
		)
	)
	(global_label "ETH_REF_CLK"
		(shape input)
		(at 351.155 168.275 180)
		(fields_autoplaced yes)
		(effects
			(font
				(size 1.27 1.27)
			)
			(justify right)
		)
		(property "Intersheetrefs" "${INTERSHEET_REFS}"
			(at 24.13 108.585 0)
			(effects
				(font
					(size 1.27 1.27)
				)
				(hide yes)
			)
		)
	)
	(global_label "ETH_RX_CLK"
		(shape input)
		(at 351.155 165.735 180)
		(fields_autoplaced yes)
		(effects
			(font
				(size 1.27 1.27)
			)
			(justify right)
		)
		(property "Intersheetrefs" "${INTERSHEET_REFS}"
			(at 24.13 108.585 0)
			(effects
				(font
					(size 1.27 1.27)
				)
				(hide yes)
			)
		)
	)
	(global_label "ETH_RX_DV"
		(shape input)
		(at 350.52 95.25 180)
		(fields_autoplaced yes)
		(effects
			(font
				(size 1.27 1.27)
			)
			(justify right)
		)
		(property "Intersheetrefs" "${INTERSHEET_REFS}"
			(at -22.225 40.64 0)
			(effects
				(font
					(size 1.27 1.27)
				)
				(hide yes)
			)
		)
	)
	(global_label "ETH_RXD2"
		(shape input)
		(at 350.52 90.17 180)
		(fields_autoplaced yes)
		(effects
			(font
				(size 1.27 1.27)
			)
			(justify right)
		)
		(property "Intersheetrefs" "${INTERSHEET_REFS}"
			(at -22.225 40.64 0)
			(effects
				(font
					(size 1.27 1.27)
				)
				(hide yes)
			)
		)
	)
	(global_label "LED_SPD"
		(shape input)
		(at 258.445 118.11 0)
		(fields_autoplaced yes)
		(effects
			(font
				(size 1.27 1.27)
			)
			(justify left)
		)
		(property "Intersheetrefs" "${INTERSHEET_REFS}"
			(at 481.33 236.22 0)
			(effects
				(font
					(size 1.27 1.27)
				)
				(hide yes)
			)
		)
	)
	(symbol
		(lib_id "antmicroCapacitors0402:C_22p_0402")
		(at 160.655 110.49 270)
		(unit 1)
		(exclude_from_sim no)
		(in_bom yes)
		(on_board yes)
		(dnp no)
		(property "Reference" "C121"
			(at 161.29 112.395 90)
			(effects
				(font
					(size 1.27 1.27)
					(thickness 0.15)
				)
				(justify left bottom)
			)
		)
		(property "Value" "C_22p_0402"
			(at 150.495 130.81 0)
			(effects
				(font
					(size 1.27 1.27)
					(thickness 0.15)
				)
				(justify left bottom)
				(hide yes)
			)
		)
		(property "Footprint" "antmicro-footprints:C_0402_1005Metric"
			(at 147.955 130.81 0)
			(effects
				(font
					(size 1.27 1.27)
					(thickness 0.15)
				)
				(justify left bottom)
				(hide yes)
			)
		)
		(property "Datasheet" " "
			(at 145.415 130.81 0)
			(effects
				(font
					(size 1.27 1.27)
					(thickness 0.15)
				)
				(justify left bottom)
				(hide yes)
			)
		)
		(property "Description" ""
			(at 160.655 110.49 0)
			(effects
				(font
					(size 1.27 1.27)
				)
			)
		)
		(property "Manufacturer" "Yaego"
			(at 140.335 130.81 0)
			(effects
				(font
					(size 1.27 1.27)
					(thickness 0.15)
				)
				(justify left bottom)
				(hide yes)
			)
		)
		(property "MPN" "CC0402JRNPO9BN220"
			(at 142.875 130.81 0)
			(effects
				(font
					(size 1.27 1.27)
					(thickness 0.15)
				)
				(justify left bottom)
				(hide yes)
			)
		)
		(property "Val" "22p"
			(at 161.29 116.205 90)
			(effects
				(font
					(size 1.27 1.27)
					(thickness 0.15)
				)
				(justify left bottom)
			)
		)
		(property "License" "Apache-2.0"
			(at 137.795 130.81 0)
			(effects
				(font
					(size 1.27 1.27)
					(thickness 0.15)
				)
				(justify left bottom)
				(hide yes)
			)
		)
		(property "Author" "Antmicro"
			(at 135.255 130.81 0)
			(effects
				(font
					(size 1.27 1.27)
					(thickness 0.15)
				)
				(justify left bottom)
				(hide yes)
			)
		)
		(property "Voltage" ""
			(at 132.715 130.81 0)
			(effects
				(font
					(size 1.27 1.27)
				)
				(justify left bottom)
				(hide yes)
			)
		)
		(property "Dielectric" ""
			(at 130.175 130.81 0)
			(effects
				(font
					(size 1.27 1.27)
				)
				(justify left bottom)
				(hide yes)
			)
		)
		(pin "1"
		)
		(pin "2"
		)
		(instances
			(project "lpddr4-test-board"
				(path ""
					(reference "C121")
					(unit 1)
				)
			)
		)
	)
	(symbol
		(lib_id "antmicroCapacitors0402:C_22p_0402")
		(at 178.435 110.49 270)
		(unit 1)
		(exclude_from_sim no)
		(in_bom yes)
		(on_board yes)
		(dnp no)
		(property "Reference" "C122"
			(at 179.07 112.395 90)
			(effects
				(font
					(size 1.27 1.27)
					(thickness 0.15)
				)
				(justify left bottom)
			)
		)
		(property "Value" "C_22p_0402"
			(at 168.275 130.81 0)
			(effects
				(font
					(size 1.27 1.27)
					(thickness 0.15)
				)
				(justify left bottom)
				(hide yes)
			)
		)
		(property "Footprint" "antmicro-footprints:C_0402_1005Metric"
			(at 165.735 130.81 0)
			(effects
				(font
					(size 1.27 1.27)
					(thickness 0.15)
				)
				(justify left bottom)
				(hide yes)
			)
		)
		(property "Datasheet" " "
			(at 163.195 130.81 0)
			(effects
				(font
					(size 1.27 1.27)
					(thickness 0.15)
				)
				(justify left bottom)
				(hide yes)
			)
		)
		(property "Description" ""
			(at 178.435 110.49 0)
			(effects
				(font
					(size 1.27 1.27)
				)
			)
		)
		(property "Manufacturer" "Yaego"
			(at 158.115 130.81 0)
			(effects
				(font
					(size 1.27 1.27)
					(thickness 0.15)
				)
				(justify left bottom)
				(hide yes)
			)
		)
		(property "MPN" "CC0402JRNPO9BN220"
			(at 160.655 130.81 0)
			(effects
				(font
					(size 1.27 1.27)
					(thickness 0.15)
				)
				(justify left bottom)
				(hide yes)
			)
		)
		(property "Val" "22p"
			(at 179.07 116.205 90)
			(effects
				(font
					(size 1.27 1.27)
					(thickness 0.15)
				)
				(justify left bottom)
			)
		)
		(property "License" "Apache-2.0"
			(at 155.575 130.81 0)
			(effects
				(font
					(size 1.27 1.27)
					(thickness 0.15)
				)
				(justify left bottom)
				(hide yes)
			)
		)
		(property "Author" "Antmicro"
			(at 153.035 130.81 0)
			(effects
				(font
					(size 1.27 1.27)
					(thickness 0.15)
				)
				(justify left bottom)
				(hide yes)
			)
		)
		(property "Voltage" ""
			(at 150.495 130.81 0)
			(effects
				(font
					(size 1.27 1.27)
				)
				(justify left bottom)
				(hide yes)
			)
		)
		(property "Dielectric" ""
			(at 147.955 130.81 0)
			(effects
				(font
					(size 1.27 1.27)
				)
				(justify left bottom)
				(hide yes)
			)
		)
		(pin "1"
		)
		(pin "2"
		)
		(instances
			(project "lpddr4-test-board"
				(path ""
					(reference "C122")
					(unit 1)
				)
			)
		)
	)
	(symbol
		(lib_id "antmicroResonators:Resonator_25MHz_ABM8G")
		(at 165.735 107.95 0)
		(unit 1)
		(exclude_from_sim no)
		(in_bom yes)
		(on_board yes)
		(dnp no)
		(property "Reference" "Y2"
			(at 167.64 101.6 0)
			(effects
				(font
					(size 1.27 1.27)
					(thickness 0.15)
				)
				(justify left bottom)
			)
		)
		(property "Value" "Oscillator_SMD_25MHz_KX-7"
			(at 169.545 102.235 0)
			(effects
				(font
					(size 1.27 1.27)
					(thickness 0.15)
				)
				(hide yes)
			)
		)
		(property "Footprint" "antmicro-footprints:Resonator_SMD_Abracon_ABM8G_3.2x2.5mm"
			(at 180.975 123.19 0)
			(effects
				(font
					(size 1.27 1.27)
					(thickness 0.15)
				)
				(justify left bottom)
				(hide yes)
			)
		)
		(property "Datasheet" "https://abracon.com/Resonators/ABM8G.pdf"
			(at 180.975 125.73 0)
			(effects
				(font
					(size 1.27 1.27)
					(thickness 0.15)
				)
				(justify left bottom)
				(hide yes)
			)
		)
		(property "Description" ""
			(at 165.735 107.95 0)
			(effects
				(font
					(size 1.27 1.27)
				)
			)
		)
		(property "MPN" "ABM8G-25.000MHZ-18-D2Y-T3"
			(at 180.975 115.57 0)
			(effects
				(font
					(size 1.27 1.27)
					(thickness 0.15)
				)
				(justify left bottom)
				(hide yes)
			)
		)
		(property "Manufacturer" "Abracon"
			(at 180.975 128.27 0)
			(effects
				(font
					(size 1.27 1.27)
					(thickness 0.15)
				)
				(justify left bottom)
				(hide yes)
			)
		)
		(property "Val" "25 MHz"
			(at 166.37 104.14 0)
			(effects
				(font
					(size 1.27 1.27)
					(thickness 0.15)
				)
				(justify left bottom)
			)
		)
		(property "Author" "Antmicro"
			(at 180.975 130.81 0)
			(effects
				(font
					(size 1.27 1.27)
					(thickness 0.15)
				)
				(justify left bottom)
				(hide yes)
			)
		)
		(property "License" "Apache-2.0"
			(at 180.975 133.35 0)
			(effects
				(font
					(size 1.27 1.27)
					(thickness 0.15)
				)
				(justify left bottom)
				(hide yes)
			)
		)
		(pin "1"
		)
		(pin "2"
		)
		(pin "3"
		)
		(pin "4"
		)
		(instances
			(project "lpddr4-test-board"
				(path ""
					(reference "Y2")
					(unit 1)
				)
			)
		)
	)
	(symbol
		(lib_id "antmicroResistors0402:R_1M8_0402")
		(at 167.005 97.79 0)
		(unit 1)
		(exclude_from_sim no)
		(in_bom yes)
		(on_board yes)
		(dnp no)
		(property "Reference" "R73"
			(at 172.085 97.79 0)
			(effects
				(font
					(size 1.27 1.27)
					(thickness 0.15)
				)
				(justify left bottom)
			)
		)
		(property "Value" "R_1M8_0402"
			(at 187.325 110.49 0)
			(effects
				(font
					(size 1.27 1.27)
					(thickness 0.15)
				)
				(justify left bottom)
				(hide yes)
			)
		)
		(property "Footprint" "antmicro-footprints:R_0402_1005Metric"
			(at 187.325 113.03 0)
			(effects
				(font
					(size 1.27 1.27)
					(thickness 0.15)
				)
				(justify left bottom)
				(hide yes)
			)
		)
		(property "Datasheet" "https://www.bourns.com/docs/product-datasheets/cr.pdf"
			(at 187.325 115.57 0)
			(effects
				(font
					(size 1.27 1.27)
					(thickness 0.15)
				)
				(justify left bottom)
				(hide yes)
			)
		)
		(property "Description" ""
			(at 167.005 97.79 0)
			(effects
				(font
					(size 1.27 1.27)
				)
			)
		)
		(property "Manufacturer" "Bourns"
			(at 187.325 120.65 0)
			(effects
				(font
					(size 1.27 1.27)
					(thickness 0.15)
				)
				(justify left bottom)
				(hide yes)
			)
		)
		(property "MPN" "CR0402-FX-1804GLF"
			(at 187.325 118.11 0)
			(effects
				(font
					(size 1.27 1.27)
					(thickness 0.15)
				)
				(justify left bottom)
				(hide yes)
			)
		)
		(property "Val" "1M8"
			(at 163.195 97.79 0)
			(effects
				(font
					(size 1.27 1.27)
					(thickness 0.15)
				)
				(justify left bottom)
			)
		)
		(property "License" "Apache-2.0"
			(at 187.325 123.19 0)
			(effects
				(font
					(size 1.27 1.27)
					(thickness 0.15)
				)
				(justify left bottom)
				(hide yes)
			)
		)
		(property "Author" "Antmicro"
			(at 187.325 125.73 0)
			(effects
				(font
					(size 1.27 1.27)
					(thickness 0.15)
				)
				(justify left bottom)
				(hide yes)
			)
		)
		(property "Tolerance" "1%"
			(at 187.325 107.95 0)
			(effects
				(font
					(size 1.27 1.27)
				)
				(justify left bottom)
				(hide yes)
			)
		)
		(pin "1"
		)
		(pin "2"
		)
		(instances
			(project "lpddr4-test-board"
				(path ""
					(reference "R73")
					(unit 1)
				)
			)
		)
	)
	(symbol
		(lib_id "antmicroInterfaceControllers:KSZ9031RNXCA")
		(at 211.455 73.66 0)
		(unit 1)
		(exclude_from_sim no)
		(in_bom yes)
		(on_board yes)
		(dnp no)
		(property "Reference" "U6"
			(at 213.995 67.945 0)
			(effects
				(font
					(size 1.27 1.27)
					(thickness 0.15)
				)
				(justify left bottom)
			)
		)
		(property "Value" "KSZ9031RNXCA"
			(at 213.995 70.485 0)
			(effects
				(font
					(size 1.27 1.27)
					(thickness 0.15)
				)
				(justify left bottom)
			)
		)
		(property "Footprint" "antmicro-footprints:QFN-48-1EP_7x7x0.9mm_P0.5mm_EP3.5x3.5mm"
			(at 287.655 83.82 0)
			(effects
				(font
					(size 1.27 1.27)
					(thickness 0.15)
				)
				(justify left bottom)
				(hide yes)
			)
		)
		(property "Datasheet" "http://ww1.microchip.com/downloads/en/DeviceDoc/00002117F.pdf"
			(at 287.655 86.36 0)
			(effects
				(font
					(size 1.27 1.27)
					(thickness 0.15)
				)
				(justify left bottom)
				(hide yes)
			)
		)
		(property "Description" ""
			(at 211.455 73.66 0)
			(effects
				(font
					(size 1.27 1.27)
				)
			)
		)
		(property "Manufacturer" "Microchip Technology"
			(at 287.655 88.9 0)
			(effects
				(font
					(size 1.27 1.27)
					(thickness 0.15)
				)
				(justify left bottom)
				(hide yes)
			)
		)
		(property "MPN" "KSZ9031RNXCA"
			(at 287.655 91.44 0)
			(effects
				(font
					(size 1.27 1.27)
					(thickness 0.15)
				)
				(justify left bottom)
				(hide yes)
			)
		)
		(property "Author" "Antmicro"
			(at 287.655 93.98 0)
			(effects
				(font
					(size 1.27 1.27)
					(thickness 0.15)
				)
				(justify left bottom)
				(hide yes)
			)
		)
		(property "License" "Apache-2.0"
			(at 287.655 96.52 0)
			(effects
				(font
					(size 1.27 1.27)
					(thickness 0.15)
				)
				(justify left bottom)
				(hide yes)
			)
		)
		(pin "1"
		)
		(pin "10"
		)
		(pin "11"
		)
		(pin "12"
		)
		(pin "13"
		)
		(pin "14"
		)
		(pin "15"
		)
		(pin "16"
		)
		(pin "17"
		)
		(pin "18"
		)
		(pin "19"
		)
		(pin "2"
		)
		(pin "20"
		)
		(pin "21"
		)
		(pin "22"
		)
		(pin "23"
		)
		(pin "24"
		)
		(pin "25"
		)
		(pin "26"
		)
		(pin "27"
		)
		(pin "28"
		)
		(pin "29"
		)
		(pin "3"
		)
		(pin "30"
		)
		(pin "31"
		)
		(pin "32"
		)
		(pin "33"
		)
		(pin "34"
		)
		(pin "35"
		)
		(pin "36"
		)
		(pin "37"
		)
		(pin "38"
		)
		(pin "39"
		)
		(pin "4"
		)
		(pin "40"
		)
		(pin "41"
		)
		(pin "42"
		)
		(pin "43"
		)
		(pin "44"
		)
		(pin "45"
		)
		(pin "46"
		)
		(pin "47"
		)
		(pin "48"
		)
		(pin "49"
		)
		(pin "5"
		)
		(pin "6"
		)
		(pin "7"
		)
		(pin "8"
		)
		(pin "9"
		)
		(instances
			(project "lpddr4-test-board"
				(path ""
					(reference "U6")
					(unit 1)
				)
			)
		)
	)
	(symbol
		(lib_id "antmicroResistors0402:R_12k1_0402")
		(at 258.445 129.54 90)
		(unit 1)
		(exclude_from_sim no)
		(in_bom yes)
		(on_board yes)
		(dnp no)
		(property "Reference" "R72"
			(at 259.715 127 90)
			(effects
				(font
					(size 1.27 1.27)
					(thickness 0.15)
				)
				(justify right top)
			)
		)
		(property "Value" "R_12k1_0402"
			(at 271.145 109.22 0)
			(effects
				(font
					(size 1.27 1.27)
					(thickness 0.15)
				)
				(justify left bottom)
				(hide yes)
			)
		)
		(property "Footprint" "antmicro-footprints:R_0402_1005Metric"
			(at 273.685 109.22 0)
			(effects
				(font
					(size 1.27 1.27)
					(thickness 0.15)
				)
				(justify left bottom)
				(hide yes)
			)
		)
		(property "Datasheet" "https://www.bourns.com/docs/product-datasheets/cr.pdf"
			(at 276.225 109.22 0)
			(effects
				(font
					(size 1.27 1.27)
					(thickness 0.15)
				)
				(justify left bottom)
				(hide yes)
			)
		)
		(property "Description" ""
			(at 258.445 129.54 0)
			(effects
				(font
					(size 1.27 1.27)
				)
			)
		)
		(property "Manufacturer" "Bourns"
			(at 281.305 109.22 0)
			(effects
				(font
					(size 1.27 1.27)
					(thickness 0.15)
				)
				(justify left bottom)
				(hide yes)
			)
		)
		(property "MPN" "CR0402-FX-1212GLF"
			(at 278.765 109.22 0)
			(effects
				(font
					(size 1.27 1.27)
					(thickness 0.15)
				)
				(justify left bottom)
				(hide yes)
			)
		)
		(property "Val" "12k1"
			(at 259.715 128.9049 90)
			(effects
				(font
					(size 1.27 1.27)
					(thickness 0.15)
				)
				(justify right top)
			)
		)
		(property "License" "Apache-2.0"
			(at 283.845 109.22 0)
			(effects
				(font
					(size 1.27 1.27)
					(thickness 0.15)
				)
				(justify left bottom)
				(hide yes)
			)
		)
		(property "Author" "Antmicro"
			(at 286.385 109.22 0)
			(effects
				(font
					(size 1.27 1.27)
					(thickness 0.15)
				)
				(justify left bottom)
				(hide yes)
			)
		)
		(property "Tolerance" "1%"
			(at 268.605 109.22 0)
			(effects
				(font
					(size 1.27 1.27)
				)
				(justify left bottom)
				(hide yes)
			)
		)
		(pin "1"
		)
		(pin "2"
		)
		(instances
			(project "lpddr4-test-board"
				(path ""
					(reference "R72")
					(unit 1)
				)
			)
		)
	)
	(symbol
		(lib_id "antmicropower:GND")
		(at 258.445 135.89 0)
		(unit 1)
		(exclude_from_sim no)
		(in_bom yes)
		(on_board yes)
		(dnp no)
		(property "Reference" "#PWR0141"
			(at 267.335 138.43 0)
			(effects
				(font
					(size 1.27 1.27)
					(thickness 0.15)
				)
				(justify left bottom)
				(hide yes)
			)
		)
		(property "Value" "GND"
			(at 256.54 140.335 0)
			(effects
				(font
					(size 1.27 1.27)
					(thickness 0.15)
				)
				(justify left bottom)
			)
		)
		(property "Footprint" ""
			(at 267.335 143.51 0)
			(effects
				(font
					(size 1.27 1.27)
					(thickness 0.15)
				)
				(justify left bottom)
				(hide yes)
			)
		)
		(property "Datasheet" ""
			(at 267.335 148.59 0)
			(effects
				(font
					(size 1.27 1.27)
					(thickness 0.15)
				)
				(justify left bottom)
				(hide yes)
			)
		)
		(property "Description" ""
			(at 258.445 135.89 0)
			(effects
				(font
					(size 1.27 1.27)
				)
			)
		)
		(property "Author" "Antmicro"
			(at 267.335 143.51 0)
			(effects
				(font
					(size 1.27 1.27)
					(thickness 0.15)
				)
				(justify left bottom)
				(hide yes)
			)
		)
		(property "License" "Apache-2.0"
			(at 267.335 146.05 0)
			(effects
				(font
					(size 1.27 1.27)
					(thickness 0.15)
				)
				(justify left bottom)
				(hide yes)
			)
		)
		(pin "1"
		)
		(instances
			(project "lpddr4-test-board"
				(path ""
					(reference "#PWR0141")
					(unit 1)
				)
			)
		)
	)
	(symbol
		(lib_id "antmicropower:GND")
		(at 178.435 116.84 0)
		(unit 1)
		(exclude_from_sim no)
		(in_bom yes)
		(on_board yes)
		(dnp no)
		(property "Reference" "#PWR0142"
			(at 187.325 119.38 0)
			(effects
				(font
					(size 1.27 1.27)
					(thickness 0.15)
				)
				(justify left bottom)
				(hide yes)
			)
		)
		(property "Value" "GND"
			(at 176.53 121.285 0)
			(effects
				(font
					(size 1.27 1.27)
					(thickness 0.15)
				)
				(justify left bottom)
			)
		)
		(property "Footprint" ""
			(at 187.325 124.46 0)
			(effects
				(font
					(size 1.27 1.27)
					(thickness 0.15)
				)
				(justify left bottom)
				(hide yes)
			)
		)
		(property "Datasheet" ""
			(at 187.325 129.54 0)
			(effects
				(font
					(size 1.27 1.27)
					(thickness 0.15)
				)
				(justify left bottom)
				(hide yes)
			)
		)
		(property "Description" ""
			(at 178.435 116.84 0)
			(effects
				(font
					(size 1.27 1.27)
				)
			)
		)
		(property "Author" "Antmicro"
			(at 187.325 124.46 0)
			(effects
				(font
					(size 1.27 1.27)
					(thickness 0.15)
				)
				(justify left bottom)
				(hide yes)
			)
		)
		(property "License" "Apache-2.0"
			(at 187.325 127 0)
			(effects
				(font
					(size 1.27 1.27)
					(thickness 0.15)
				)
				(justify left bottom)
				(hide yes)
			)
		)
		(pin "1"
		)
		(instances
			(project "lpddr4-test-board"
				(path ""
					(reference "#PWR0142")
					(unit 1)
				)
			)
		)
	)
	(symbol
		(lib_id "antmicroResistors0402:R_10k2_0402")
		(at 361.315 153.035 0)
		(unit 1)
		(exclude_from_sim no)
		(in_bom no)
		(on_board yes)
		(dnp yes)
		(property "Reference" "R74"
			(at 366.395 153.035 0)
			(effects
				(font
					(size 1.27 1.27)
					(thickness 0.15)
				)
				(justify left bottom)
			)
		)
		(property "Value" "R_10k2_0402"
			(at 381.635 165.735 0)
			(effects
				(font
					(size 1.27 1.27)
					(thickness 0.15)
				)
				(justify left bottom)
				(hide yes)
			)
		)
		(property "Footprint" "antmicro-footprints:R_0402_1005Metric"
			(at 381.635 168.275 0)
			(effects
				(font
					(size 1.27 1.27)
					(thickness 0.15)
				)
				(justify left bottom)
				(hide yes)
			)
		)
		(property "Datasheet" "https://www.bourns.com/docs/product-datasheets/cr.pdf"
			(at 381.635 170.815 0)
			(effects
				(font
					(size 1.27 1.27)
					(thickness 0.15)
				)
				(justify left bottom)
				(hide yes)
			)
		)
		(property "Description" ""
			(at 361.315 153.035 0)
			(effects
				(font
					(size 1.27 1.27)
				)
			)
		)
		(property "Manufacturer" "Bourns"
			(at 381.635 175.895 0)
			(effects
				(font
					(size 1.27 1.27)
					(thickness 0.15)
				)
				(justify left bottom)
				(hide yes)
			)
		)
		(property "MPN" "CR0402-FX-1022GLF"
			(at 381.635 173.355 0)
			(effects
				(font
					(size 1.27 1.27)
					(thickness 0.15)
				)
				(justify left bottom)
				(hide yes)
			)
		)
		(property "Val" "10k2"
			(at 356.235 153.035 0)
			(effects
				(font
					(size 1.27 1.27)
					(thickness 0.15)
				)
				(justify left bottom)
			)
		)
		(property "License" "Apache-2.0"
			(at 381.635 178.435 0)
			(effects
				(font
					(size 1.27 1.27)
					(thickness 0.15)
				)
				(justify left bottom)
				(hide yes)
			)
		)
		(property "Author" "Antmicro"
			(at 381.635 180.975 0)
			(effects
				(font
					(size 1.27 1.27)
					(thickness 0.15)
				)
				(justify left bottom)
				(hide yes)
			)
		)
		(property "Tolerance" "1%"
			(at 381.635 163.195 0)
			(effects
				(font
					(size 1.27 1.27)
				)
				(justify left bottom)
				(hide yes)
			)
		)
		(pin "1"
		)
		(pin "2"
		)
		(instances
			(project "lpddr4-test-board"
				(path ""
					(reference "R74")
					(unit 1)
				)
			)
		)
	)
	(symbol
		(lib_id "antmicroResistors0402:R_10k2_0402")
		(at 361.315 155.575 0)
		(unit 1)
		(exclude_from_sim no)
		(in_bom no)
		(on_board yes)
		(dnp yes)
		(property "Reference" "R75"
			(at 366.395 155.575 0)
			(effects
				(font
					(size 1.27 1.27)
					(thickness 0.15)
				)
				(justify left bottom)
			)
		)
		(property "Value" "R_10k2_0402"
			(at 381.635 168.275 0)
			(effects
				(font
					(size 1.27 1.27)
					(thickness 0.15)
				)
				(justify left bottom)
				(hide yes)
			)
		)
		(property "Footprint" "antmicro-footprints:R_0402_1005Metric"
			(at 381.635 170.815 0)
			(effects
				(font
					(size 1.27 1.27)
					(thickness 0.15)
				)
				(justify left bottom)
				(hide yes)
			)
		)
		(property "Datasheet" "https://www.bourns.com/docs/product-datasheets/cr.pdf"
			(at 381.635 173.355 0)
			(effects
				(font
					(size 1.27 1.27)
					(thickness 0.15)
				)
				(justify left bottom)
				(hide yes)
			)
		)
		(property "Description" ""
			(at 361.315 155.575 0)
			(effects
				(font
					(size 1.27 1.27)
				)
			)
		)
		(property "Manufacturer" "Bourns"
			(at 381.635 178.435 0)
			(effects
				(font
					(size 1.27 1.27)
					(thickness 0.15)
				)
				(justify left bottom)
				(hide yes)
			)
		)
		(property "MPN" "CR0402-FX-1022GLF"
			(at 381.635 175.895 0)
			(effects
				(font
					(size 1.27 1.27)
					(thickness 0.15)
				)
				(justify left bottom)
				(hide yes)
			)
		)
		(property "Val" "10k2"
			(at 356.235 155.575 0)
			(effects
				(font
					(size 1.27 1.27)
					(thickness 0.15)
				)
				(justify left bottom)
			)
		)
		(property "License" "Apache-2.0"
			(at 381.635 180.975 0)
			(effects
				(font
					(size 1.27 1.27)
					(thickness 0.15)
				)
				(justify left bottom)
				(hide yes)
			)
		)
		(property "Author" "Antmicro"
			(at 381.635 183.515 0)
			(effects
				(font
					(size 1.27 1.27)
					(thickness 0.15)
				)
				(justify left bottom)
				(hide yes)
			)
		)
		(property "Tolerance" "1%"
			(at 381.635 165.735 0)
			(effects
				(font
					(size 1.27 1.27)
				)
				(justify left bottom)
				(hide yes)
			)
		)
		(pin "1"
		)
		(pin "2"
		)
		(instances
			(project "lpddr4-test-board"
				(path ""
					(reference "R75")
					(unit 1)
				)
			)
		)
	)
	(symbol
		(lib_id "antmicroResistors0402:R_10k2_0402")
		(at 361.315 158.115 0)
		(unit 1)
		(exclude_from_sim no)
		(in_bom yes)
		(on_board yes)
		(dnp no)
		(property "Reference" "R76"
			(at 366.395 158.115 0)
			(effects
				(font
					(size 1.27 1.27)
					(thickness 0.15)
				)
				(justify left bottom)
			)
		)
		(property "Value" "R_10k2_0402"
			(at 381.635 170.815 0)
			(effects
				(font
					(size 1.27 1.27)
					(thickness 0.15)
				)
				(justify left bottom)
				(hide yes)
			)
		)
		(property "Footprint" "antmicro-footprints:R_0402_1005Metric"
			(at 381.635 173.355 0)
			(effects
				(font
					(size 1.27 1.27)
					(thickness 0.15)
				)
				(justify left bottom)
				(hide yes)
			)
		)
		(property "Datasheet" "https://www.bourns.com/docs/product-datasheets/cr.pdf"
			(at 381.635 175.895 0)
			(effects
				(font
					(size 1.27 1.27)
					(thickness 0.15)
				)
				(justify left bottom)
				(hide yes)
			)
		)
		(property "Description" ""
			(at 361.315 158.115 0)
			(effects
				(font
					(size 1.27 1.27)
				)
			)
		)
		(property "Manufacturer" "Bourns"
			(at 381.635 180.975 0)
			(effects
				(font
					(size 1.27 1.27)
					(thickness 0.15)
				)
				(justify left bottom)
				(hide yes)
			)
		)
		(property "MPN" "CR0402-FX-1022GLF"
			(at 381.635 178.435 0)
			(effects
				(font
					(size 1.27 1.27)
					(thickness 0.15)
				)
				(justify left bottom)
				(hide yes)
			)
		)
		(property "Val" "10k2"
			(at 356.235 158.115 0)
			(effects
				(font
					(size 1.27 1.27)
					(thickness 0.15)
				)
				(justify left bottom)
			)
		)
		(property "License" "Apache-2.0"
			(at 381.635 183.515 0)
			(effects
				(font
					(size 1.27 1.27)
					(thickness 0.15)
				)
				(justify left bottom)
				(hide yes)
			)
		)
		(property "Author" "Antmicro"
			(at 381.635 186.055 0)
			(effects
				(font
					(size 1.27 1.27)
					(thickness 0.15)
				)
				(justify left bottom)
				(hide yes)
			)
		)
		(property "Tolerance" "1%"
			(at 381.635 168.275 0)
			(effects
				(font
					(size 1.27 1.27)
				)
				(justify left bottom)
				(hide yes)
			)
		)
		(pin "1"
		)
		(pin "2"
		)
		(instances
			(project "lpddr4-test-board"
				(path ""
					(reference "R76")
					(unit 1)
				)
			)
		)
	)
	(symbol
		(lib_id "antmicroResistors0402:R_10k2_0402")
		(at 361.315 160.655 0)
		(unit 1)
		(exclude_from_sim no)
		(in_bom yes)
		(on_board yes)
		(dnp no)
		(property "Reference" "R77"
			(at 366.395 160.655 0)
			(effects
				(font
					(size 1.27 1.27)
					(thickness 0.15)
				)
				(justify left bottom)
			)
		)
		(property "Value" "R_10k2_0402"
			(at 381.635 173.355 0)
			(effects
				(font
					(size 1.27 1.27)
					(thickness 0.15)
				)
				(justify left bottom)
				(hide yes)
			)
		)
		(property "Footprint" "antmicro-footprints:R_0402_1005Metric"
			(at 381.635 175.895 0)
			(effects
				(font
					(size 1.27 1.27)
					(thickness 0.15)
				)
				(justify left bottom)
				(hide yes)
			)
		)
		(property "Datasheet" "https://www.bourns.com/docs/product-datasheets/cr.pdf"
			(at 381.635 178.435 0)
			(effects
				(font
					(size 1.27 1.27)
					(thickness 0.15)
				)
				(justify left bottom)
				(hide yes)
			)
		)
		(property "Description" ""
			(at 361.315 160.655 0)
			(effects
				(font
					(size 1.27 1.27)
				)
			)
		)
		(property "Manufacturer" "Bourns"
			(at 381.635 183.515 0)
			(effects
				(font
					(size 1.27 1.27)
					(thickness 0.15)
				)
				(justify left bottom)
				(hide yes)
			)
		)
		(property "MPN" "CR0402-FX-1022GLF"
			(at 381.635 180.975 0)
			(effects
				(font
					(size 1.27 1.27)
					(thickness 0.15)
				)
				(justify left bottom)
				(hide yes)
			)
		)
		(property "Val" "10k2"
			(at 356.235 160.655 0)
			(effects
				(font
					(size 1.27 1.27)
					(thickness 0.15)
				)
				(justify left bottom)
			)
		)
		(property "License" "Apache-2.0"
			(at 381.635 186.055 0)
			(effects
				(font
					(size 1.27 1.27)
					(thickness 0.15)
				)
				(justify left bottom)
				(hide yes)
			)
		)
		(property "Author" "Antmicro"
			(at 381.635 188.595 0)
			(effects
				(font
					(size 1.27 1.27)
					(thickness 0.15)
				)
				(justify left bottom)
				(hide yes)
			)
		)
		(property "Tolerance" "1%"
			(at 381.635 170.815 0)
			(effects
				(font
					(size 1.27 1.27)
				)
				(justify left bottom)
				(hide yes)
			)
		)
		(pin "1"
		)
		(pin "2"
		)
		(instances
			(project "lpddr4-test-board"
				(path ""
					(reference "R77")
					(unit 1)
				)
			)
		)
	)
	(symbol
		(lib_id "antmicroResistors0402:R_10k2_0402")
		(at 361.315 163.195 0)
		(unit 1)
		(exclude_from_sim no)
		(in_bom no)
		(on_board yes)
		(dnp yes)
		(property "Reference" "R78"
			(at 366.395 163.195 0)
			(effects
				(font
					(size 1.27 1.27)
					(thickness 0.15)
				)
				(justify left bottom)
			)
		)
		(property "Value" "R_10k2_0402"
			(at 381.635 175.895 0)
			(effects
				(font
					(size 1.27 1.27)
					(thickness 0.15)
				)
				(justify left bottom)
				(hide yes)
			)
		)
		(property "Footprint" "antmicro-footprints:R_0402_1005Metric"
			(at 381.635 178.435 0)
			(effects
				(font
					(size 1.27 1.27)
					(thickness 0.15)
				)
				(justify left bottom)
				(hide yes)
			)
		)
		(property "Datasheet" "https://www.bourns.com/docs/product-datasheets/cr.pdf"
			(at 381.635 180.975 0)
			(effects
				(font
					(size 1.27 1.27)
					(thickness 0.15)
				)
				(justify left bottom)
				(hide yes)
			)
		)
		(property "Description" ""
			(at 361.315 163.195 0)
			(effects
				(font
					(size 1.27 1.27)
				)
			)
		)
		(property "Manufacturer" "Bourns"
			(at 381.635 186.055 0)
			(effects
				(font
					(size 1.27 1.27)
					(thickness 0.15)
				)
				(justify left bottom)
				(hide yes)
			)
		)
		(property "MPN" "CR0402-FX-1022GLF"
			(at 381.635 183.515 0)
			(effects
				(font
					(size 1.27 1.27)
					(thickness 0.15)
				)
				(justify left bottom)
				(hide yes)
			)
		)
		(property "Val" "10k2"
			(at 356.235 163.195 0)
			(effects
				(font
					(size 1.27 1.27)
					(thickness 0.15)
				)
				(justify left bottom)
			)
		)
		(property "License" "Apache-2.0"
			(at 381.635 188.595 0)
			(effects
				(font
					(size 1.27 1.27)
					(thickness 0.15)
				)
				(justify left bottom)
				(hide yes)
			)
		)
		(property "Author" "Antmicro"
			(at 381.635 191.135 0)
			(effects
				(font
					(size 1.27 1.27)
					(thickness 0.15)
				)
				(justify left bottom)
				(hide yes)
			)
		)
		(property "Tolerance" "1%"
			(at 381.635 173.355 0)
			(effects
				(font
					(size 1.27 1.27)
				)
				(justify left bottom)
				(hide yes)
			)
		)
		(pin "1"
		)
		(pin "2"
		)
		(instances
			(project "lpddr4-test-board"
				(path ""
					(reference "R78")
					(unit 1)
				)
			)
		)
	)
	(symbol
		(lib_id "antmicroResistors0402:R_10k2_0402")
		(at 361.315 165.735 0)
		(unit 1)
		(exclude_from_sim no)
		(in_bom no)
		(on_board yes)
		(dnp yes)
		(property "Reference" "R79"
			(at 366.395 165.735 0)
			(effects
				(font
					(size 1.27 1.27)
					(thickness 0.15)
				)
				(justify left bottom)
			)
		)
		(property "Value" "R_10k2_0402"
			(at 381.635 178.435 0)
			(effects
				(font
					(size 1.27 1.27)
					(thickness 0.15)
				)
				(justify left bottom)
				(hide yes)
			)
		)
		(property "Footprint" "antmicro-footprints:R_0402_1005Metric"
			(at 381.635 180.975 0)
			(effects
				(font
					(size 1.27 1.27)
					(thickness 0.15)
				)
				(justify left bottom)
				(hide yes)
			)
		)
		(property "Datasheet" "https://www.bourns.com/docs/product-datasheets/cr.pdf"
			(at 381.635 183.515 0)
			(effects
				(font
					(size 1.27 1.27)
					(thickness 0.15)
				)
				(justify left bottom)
				(hide yes)
			)
		)
		(property "Description" ""
			(at 361.315 165.735 0)
			(effects
				(font
					(size 1.27 1.27)
				)
			)
		)
		(property "Manufacturer" "Bourns"
			(at 381.635 188.595 0)
			(effects
				(font
					(size 1.27 1.27)
					(thickness 0.15)
				)
				(justify left bottom)
				(hide yes)
			)
		)
		(property "MPN" "CR0402-FX-1022GLF"
			(at 381.635 186.055 0)
			(effects
				(font
					(size 1.27 1.27)
					(thickness 0.15)
				)
				(justify left bottom)
				(hide yes)
			)
		)
		(property "Val" "10k2"
			(at 356.235 165.735 0)
			(effects
				(font
					(size 1.27 1.27)
					(thickness 0.15)
				)
				(justify left bottom)
			)
		)
		(property "License" "Apache-2.0"
			(at 381.635 191.135 0)
			(effects
				(font
					(size 1.27 1.27)
					(thickness 0.15)
				)
				(justify left bottom)
				(hide yes)
			)
		)
		(property "Author" "Antmicro"
			(at 381.635 193.675 0)
			(effects
				(font
					(size 1.27 1.27)
					(thickness 0.15)
				)
				(justify left bottom)
				(hide yes)
			)
		)
		(property "Tolerance" "1%"
			(at 381.635 175.895 0)
			(effects
				(font
					(size 1.27 1.27)
				)
				(justify left bottom)
				(hide yes)
			)
		)
		(pin "1"
		)
		(pin "2"
		)
		(instances
			(project "lpddr4-test-board"
				(path ""
					(reference "R79")
					(unit 1)
				)
			)
		)
	)
	(symbol
		(lib_id "antmicroResistors0402:R_10k2_0402")
		(at 361.315 168.275 0)
		(unit 1)
		(exclude_from_sim no)
		(in_bom yes)
		(on_board yes)
		(dnp no)
		(property "Reference" "R80"
			(at 366.395 168.275 0)
			(effects
				(font
					(size 1.27 1.27)
					(thickness 0.15)
				)
				(justify left bottom)
			)
		)
		(property "Value" "R_10k2_0402"
			(at 381.635 180.975 0)
			(effects
				(font
					(size 1.27 1.27)
					(thickness 0.15)
				)
				(justify left bottom)
				(hide yes)
			)
		)
		(property "Footprint" "antmicro-footprints:R_0402_1005Metric"
			(at 381.635 183.515 0)
			(effects
				(font
					(size 1.27 1.27)
					(thickness 0.15)
				)
				(justify left bottom)
				(hide yes)
			)
		)
		(property "Datasheet" "https://www.bourns.com/docs/product-datasheets/cr.pdf"
			(at 381.635 186.055 0)
			(effects
				(font
					(size 1.27 1.27)
					(thickness 0.15)
				)
				(justify left bottom)
				(hide yes)
			)
		)
		(property "Description" ""
			(at 361.315 168.275 0)
			(effects
				(font
					(size 1.27 1.27)
				)
			)
		)
		(property "Manufacturer" "Bourns"
			(at 381.635 191.135 0)
			(effects
				(font
					(size 1.27 1.27)
					(thickness 0.15)
				)
				(justify left bottom)
				(hide yes)
			)
		)
		(property "MPN" "CR0402-FX-1022GLF"
			(at 381.635 188.595 0)
			(effects
				(font
					(size 1.27 1.27)
					(thickness 0.15)
				)
				(justify left bottom)
				(hide yes)
			)
		)
		(property "Val" "10k2"
			(at 356.235 168.275 0)
			(effects
				(font
					(size 1.27 1.27)
					(thickness 0.15)
				)
				(justify left bottom)
			)
		)
		(property "License" "Apache-2.0"
			(at 381.635 193.675 0)
			(effects
				(font
					(size 1.27 1.27)
					(thickness 0.15)
				)
				(justify left bottom)
				(hide yes)
			)
		)
		(property "Author" "Antmicro"
			(at 381.635 196.215 0)
			(effects
				(font
					(size 1.27 1.27)
					(thickness 0.15)
				)
				(justify left bottom)
				(hide yes)
			)
		)
		(property "Tolerance" "1%"
			(at 381.635 178.435 0)
			(effects
				(font
					(size 1.27 1.27)
				)
				(justify left bottom)
				(hide yes)
			)
		)
		(pin "1"
		)
		(pin "2"
		)
		(instances
			(project "lpddr4-test-board"
				(path ""
					(reference "R80")
					(unit 1)
				)
			)
		)
	)
	(symbol
		(lib_id "antmicroResistors0402:R_10k2_0402")
		(at 361.315 178.435 0)
		(unit 1)
		(exclude_from_sim no)
		(in_bom yes)
		(on_board yes)
		(dnp no)
		(property "Reference" "R84"
			(at 366.395 178.435 0)
			(effects
				(font
					(size 1.27 1.27)
					(thickness 0.15)
				)
				(justify left bottom)
			)
		)
		(property "Value" "R_10k2_0402"
			(at 381.635 191.135 0)
			(effects
				(font
					(size 1.27 1.27)
					(thickness 0.15)
				)
				(justify left bottom)
				(hide yes)
			)
		)
		(property "Footprint" "antmicro-footprints:R_0402_1005Metric"
			(at 381.635 193.675 0)
			(effects
				(font
					(size 1.27 1.27)
					(thickness 0.15)
				)
				(justify left bottom)
				(hide yes)
			)
		)
		(property "Datasheet" "https://www.bourns.com/docs/product-datasheets/cr.pdf"
			(at 381.635 196.215 0)
			(effects
				(font
					(size 1.27 1.27)
					(thickness 0.15)
				)
				(justify left bottom)
				(hide yes)
			)
		)
		(property "Description" ""
			(at 361.315 178.435 0)
			(effects
				(font
					(size 1.27 1.27)
				)
			)
		)
		(property "Manufacturer" "Bourns"
			(at 381.635 201.295 0)
			(effects
				(font
					(size 1.27 1.27)
					(thickness 0.15)
				)
				(justify left bottom)
				(hide yes)
			)
		)
		(property "MPN" "CR0402-FX-1022GLF"
			(at 381.635 198.755 0)
			(effects
				(font
					(size 1.27 1.27)
					(thickness 0.15)
				)
				(justify left bottom)
				(hide yes)
			)
		)
		(property "Val" "10k2"
			(at 356.235 178.435 0)
			(effects
				(font
					(size 1.27 1.27)
					(thickness 0.15)
				)
				(justify left bottom)
			)
		)
		(property "License" "Apache-2.0"
			(at 381.635 203.835 0)
			(effects
				(font
					(size 1.27 1.27)
					(thickness 0.15)
				)
				(justify left bottom)
				(hide yes)
			)
		)
		(property "Author" "Antmicro"
			(at 381.635 206.375 0)
			(effects
				(font
					(size 1.27 1.27)
					(thickness 0.15)
				)
				(justify left bottom)
				(hide yes)
			)
		)
		(property "Tolerance" "1%"
			(at 381.635 188.595 0)
			(effects
				(font
					(size 1.27 1.27)
				)
				(justify left bottom)
				(hide yes)
			)
		)
		(pin "1"
		)
		(pin "2"
		)
		(instances
			(project "lpddr4-test-board"
				(path ""
					(reference "R84")
					(unit 1)
				)
			)
		)
	)
	(symbol
		(lib_id "antmicroResistors0402:R_10k2_0402")
		(at 361.315 170.815 0)
		(unit 1)
		(exclude_from_sim no)
		(in_bom yes)
		(on_board yes)
		(dnp no)
		(property "Reference" "R81"
			(at 366.395 170.815 0)
			(effects
				(font
					(size 1.27 1.27)
					(thickness 0.15)
				)
				(justify left bottom)
			)
		)
		(property "Value" "R_10k2_0402"
			(at 381.635 183.515 0)
			(effects
				(font
					(size 1.27 1.27)
					(thickness 0.15)
				)
				(justify left bottom)
				(hide yes)
			)
		)
		(property "Footprint" "antmicro-footprints:R_0402_1005Metric"
			(at 381.635 186.055 0)
			(effects
				(font
					(size 1.27 1.27)
					(thickness 0.15)
				)
				(justify left bottom)
				(hide yes)
			)
		)
		(property "Datasheet" "https://www.bourns.com/docs/product-datasheets/cr.pdf"
			(at 381.635 188.595 0)
			(effects
				(font
					(size 1.27 1.27)
					(thickness 0.15)
				)
				(justify left bottom)
				(hide yes)
			)
		)
		(property "Description" ""
			(at 361.315 170.815 0)
			(effects
				(font
					(size 1.27 1.27)
				)
			)
		)
		(property "Manufacturer" "Bourns"
			(at 381.635 193.675 0)
			(effects
				(font
					(size 1.27 1.27)
					(thickness 0.15)
				)
				(justify left bottom)
				(hide yes)
			)
		)
		(property "MPN" "CR0402-FX-1022GLF"
			(at 381.635 191.135 0)
			(effects
				(font
					(size 1.27 1.27)
					(thickness 0.15)
				)
				(justify left bottom)
				(hide yes)
			)
		)
		(property "Val" "10k2"
			(at 356.235 170.815 0)
			(effects
				(font
					(size 1.27 1.27)
					(thickness 0.15)
				)
				(justify left bottom)
			)
		)
		(property "License" "Apache-2.0"
			(at 381.635 196.215 0)
			(effects
				(font
					(size 1.27 1.27)
					(thickness 0.15)
				)
				(justify left bottom)
				(hide yes)
			)
		)
		(property "Author" "Antmicro"
			(at 381.635 198.755 0)
			(effects
				(font
					(size 1.27 1.27)
					(thickness 0.15)
				)
				(justify left bottom)
				(hide yes)
			)
		)
		(property "Tolerance" "1%"
			(at 381.635 180.975 0)
			(effects
				(font
					(size 1.27 1.27)
				)
				(justify left bottom)
				(hide yes)
			)
		)
		(pin "1"
		)
		(pin "2"
		)
		(instances
			(project "lpddr4-test-board"
				(path ""
					(reference "R81")
					(unit 1)
				)
			)
		)
	)
	(symbol
		(lib_id "antmicroResistors0402:R_10k2_0402")
		(at 361.315 173.355 0)
		(unit 1)
		(exclude_from_sim no)
		(in_bom yes)
		(on_board yes)
		(dnp no)
		(property "Reference" "R82"
			(at 366.395 173.355 0)
			(effects
				(font
					(size 1.27 1.27)
					(thickness 0.15)
				)
				(justify left bottom)
			)
		)
		(property "Value" "R_10k2_0402"
			(at 381.635 186.055 0)
			(effects
				(font
					(size 1.27 1.27)
					(thickness 0.15)
				)
				(justify left bottom)
				(hide yes)
			)
		)
		(property "Footprint" "antmicro-footprints:R_0402_1005Metric"
			(at 381.635 188.595 0)
			(effects
				(font
					(size 1.27 1.27)
					(thickness 0.15)
				)
				(justify left bottom)
				(hide yes)
			)
		)
		(property "Datasheet" "https://www.bourns.com/docs/product-datasheets/cr.pdf"
			(at 381.635 191.135 0)
			(effects
				(font
					(size 1.27 1.27)
					(thickness 0.15)
				)
				(justify left bottom)
				(hide yes)
			)
		)
		(property "Description" ""
			(at 361.315 173.355 0)
			(effects
				(font
					(size 1.27 1.27)
				)
			)
		)
		(property "Manufacturer" "Bourns"
			(at 381.635 196.215 0)
			(effects
				(font
					(size 1.27 1.27)
					(thickness 0.15)
				)
				(justify left bottom)
				(hide yes)
			)
		)
		(property "MPN" "CR0402-FX-1022GLF"
			(at 381.635 193.675 0)
			(effects
				(font
					(size 1.27 1.27)
					(thickness 0.15)
				)
				(justify left bottom)
				(hide yes)
			)
		)
		(property "Val" "10k2"
			(at 356.235 173.355 0)
			(effects
				(font
					(size 1.27 1.27)
					(thickness 0.15)
				)
				(justify left bottom)
			)
		)
		(property "License" "Apache-2.0"
			(at 381.635 198.755 0)
			(effects
				(font
					(size 1.27 1.27)
					(thickness 0.15)
				)
				(justify left bottom)
				(hide yes)
			)
		)
		(property "Author" "Antmicro"
			(at 381.635 201.295 0)
			(effects
				(font
					(size 1.27 1.27)
					(thickness 0.15)
				)
				(justify left bottom)
				(hide yes)
			)
		)
		(property "Tolerance" "1%"
			(at 381.635 183.515 0)
			(effects
				(font
					(size 1.27 1.27)
				)
				(justify left bottom)
				(hide yes)
			)
		)
		(pin "1"
		)
		(pin "2"
		)
		(instances
			(project "lpddr4-test-board"
				(path ""
					(reference "R82")
					(unit 1)
				)
			)
		)
	)
	(symbol
		(lib_id "antmicroCapacitors0402:C_4u7_0402")
		(at 65.405 245.11 270)
		(unit 1)
		(exclude_from_sim no)
		(in_bom yes)
		(on_board yes)
		(dnp no)
		(property "Reference" "C99"
			(at 66.04 247.015 90)
			(effects
				(font
					(size 1.27 1.27)
					(thickness 0.15)
				)
				(justify left bottom)
			)
		)
		(property "Value" "C_4u7_0402"
			(at 55.245 265.43 0)
			(effects
				(font
					(size 1.27 1.27)
					(thickness 0.15)
				)
				(justify left bottom)
				(hide yes)
			)
		)
		(property "Footprint" "antmicro-footprints:C_0402_1005Metric"
			(at 52.705 265.43 0)
			(effects
				(font
					(size 1.27 1.27)
					(thickness 0.15)
				)
				(justify left bottom)
				(hide yes)
			)
		)
		(property "Datasheet" " "
			(at 50.165 265.43 0)
			(effects
				(font
					(size 1.27 1.27)
					(thickness 0.15)
				)
				(justify left bottom)
				(hide yes)
			)
		)
		(property "Description" ""
			(at 65.405 245.11 0)
			(effects
				(font
					(size 1.27 1.27)
				)
			)
		)
		(property "Manufacturer" "Murata"
			(at 45.085 265.43 0)
			(effects
				(font
					(size 1.27 1.27)
					(thickness 0.15)
				)
				(justify left bottom)
				(hide yes)
			)
		)
		(property "MPN" "GRM155R61A475MEAAD"
			(at 47.625 265.43 0)
			(effects
				(font
					(size 1.27 1.27)
					(thickness 0.15)
				)
				(justify left bottom)
				(hide yes)
			)
		)
		(property "Val" "4u7"
			(at 66.04 250.825 90)
			(effects
				(font
					(size 1.27 1.27)
					(thickness 0.15)
				)
				(justify left bottom)
			)
		)
		(property "License" "Apache-2.0"
			(at 42.545 265.43 0)
			(effects
				(font
					(size 1.27 1.27)
					(thickness 0.15)
				)
				(justify left bottom)
				(hide yes)
			)
		)
		(property "Author" "Antmicro"
			(at 40.005 265.43 0)
			(effects
				(font
					(size 1.27 1.27)
					(thickness 0.15)
				)
				(justify left bottom)
				(hide yes)
			)
		)
		(property "Voltage" ""
			(at 37.465 265.43 0)
			(effects
				(font
					(size 1.27 1.27)
				)
				(justify left bottom)
				(hide yes)
			)
		)
		(property "Dielectric" ""
			(at 34.925 265.43 0)
			(effects
				(font
					(size 1.27 1.27)
				)
				(justify left bottom)
				(hide yes)
			)
		)
		(pin "1"
		)
		(pin "2"
		)
		(instances
			(project "lpddr4-test-board"
				(path ""
					(reference "C99")
					(unit 1)
				)
			)
		)
	)
	(symbol
		(lib_id "antmicroCapacitors0402:C_470n_0402")
		(at 72.39 245.11 270)
		(unit 1)
		(exclude_from_sim no)
		(in_bom yes)
		(on_board yes)
		(dnp no)
		(property "Reference" "C103"
			(at 73.025 247.015 90)
			(effects
				(font
					(size 1.27 1.27)
					(thickness 0.15)
				)
				(justify left bottom)
			)
		)
		(property "Value" "C_470n_0402"
			(at 62.23 265.43 0)
			(effects
				(font
					(size 1.27 1.27)
					(thickness 0.15)
				)
				(justify left bottom)
				(hide yes)
			)
		)
		(property "Footprint" "antmicro-footprints:C_0402_1005Metric"
			(at 59.69 265.43 0)
			(effects
				(font
					(size 1.27 1.27)
					(thickness 0.15)
				)
				(justify left bottom)
				(hide yes)
			)
		)
		(property "Datasheet" " "
			(at 57.15 265.43 0)
			(effects
				(font
					(size 1.27 1.27)
					(thickness 0.15)
				)
				(justify left bottom)
				(hide yes)
			)
		)
		(property "Description" ""
			(at 72.39 245.11 0)
			(effects
				(font
					(size 1.27 1.27)
				)
			)
		)
		(property "Manufacturer" "TDK"
			(at 52.07 265.43 0)
			(effects
				(font
					(size 1.27 1.27)
					(thickness 0.15)
				)
				(justify left bottom)
				(hide yes)
			)
		)
		(property "MPN" "C1005X5R1E474M050BB"
			(at 54.61 265.43 0)
			(effects
				(font
					(size 1.27 1.27)
					(thickness 0.15)
				)
				(justify left bottom)
				(hide yes)
			)
		)
		(property "Val" "470n"
			(at 73.025 250.825 90)
			(effects
				(font
					(size 1.27 1.27)
					(thickness 0.15)
				)
				(justify left bottom)
			)
		)
		(property "License" "Apache-2.0"
			(at 49.53 265.43 0)
			(effects
				(font
					(size 1.27 1.27)
					(thickness 0.15)
				)
				(justify left bottom)
				(hide yes)
			)
		)
		(property "Author" "Antmicro"
			(at 46.99 265.43 0)
			(effects
				(font
					(size 1.27 1.27)
					(thickness 0.15)
				)
				(justify left bottom)
				(hide yes)
			)
		)
		(property "Voltage" ""
			(at 44.45 265.43 0)
			(effects
				(font
					(size 1.27 1.27)
				)
				(justify left bottom)
				(hide yes)
			)
		)
		(property "Dielectric" ""
			(at 41.91 265.43 0)
			(effects
				(font
					(size 1.27 1.27)
				)
				(justify left bottom)
				(hide yes)
			)
		)
		(pin "1"
		)
		(pin "2"
		)
		(instances
			(project "lpddr4-test-board"
				(path ""
					(reference "C103")
					(unit 1)
				)
			)
		)
	)
	(symbol
		(lib_id "antmicroCapacitors0402:C_10n_0402")
		(at 79.375 245.11 270)
		(unit 1)
		(exclude_from_sim no)
		(in_bom yes)
		(on_board yes)
		(dnp no)
		(property "Reference" "C107"
			(at 80.01 247.015 90)
			(effects
				(font
					(size 1.27 1.27)
					(thickness 0.15)
				)
				(justify left bottom)
			)
		)
		(property "Value" "C_10n_0402"
			(at 69.215 265.43 0)
			(effects
				(font
					(size 1.27 1.27)
					(thickness 0.15)
				)
				(justify left bottom)
				(hide yes)
			)
		)
		(property "Footprint" "antmicro-footprints:C_0402_1005Metric"
			(at 66.675 265.43 0)
			(effects
				(font
					(size 1.27 1.27)
					(thickness 0.15)
				)
				(justify left bottom)
				(hide yes)
			)
		)
		(property "Datasheet" "https://search.murata.co.jp/Ceramy/image/img/A01X/G101/ENG/GRM155R71H103KA88-01.pdf"
			(at 64.135 265.43 0)
			(effects
				(font
					(size 1.27 1.27)
					(thickness 0.15)
				)
				(justify left bottom)
				(hide yes)
			)
		)
		(property "Description" ""
			(at 79.375 245.11 0)
			(effects
				(font
					(size 1.27 1.27)
				)
			)
		)
		(property "Manufacturer" "Murata"
			(at 59.055 265.43 0)
			(effects
				(font
					(size 1.27 1.27)
					(thickness 0.15)
				)
				(justify left bottom)
				(hide yes)
			)
		)
		(property "MPN" "GRM155R71H103KA88D"
			(at 61.595 265.43 0)
			(effects
				(font
					(size 1.27 1.27)
					(thickness 0.15)
				)
				(justify left bottom)
				(hide yes)
			)
		)
		(property "Val" "10n"
			(at 80.01 250.825 90)
			(effects
				(font
					(size 1.27 1.27)
					(thickness 0.15)
				)
				(justify left bottom)
			)
		)
		(property "License" "Apache-2.0"
			(at 56.515 265.43 0)
			(effects
				(font
					(size 1.27 1.27)
					(thickness 0.15)
				)
				(justify left bottom)
				(hide yes)
			)
		)
		(property "Author" "Antmicro"
			(at 53.975 265.43 0)
			(effects
				(font
					(size 1.27 1.27)
					(thickness 0.15)
				)
				(justify left bottom)
				(hide yes)
			)
		)
		(property "Voltage" "50V"
			(at 51.435 265.43 0)
			(effects
				(font
					(size 1.27 1.27)
				)
				(justify left bottom)
				(hide yes)
			)
		)
		(property "Dielectric" "X7R"
			(at 48.895 265.43 0)
			(effects
				(font
					(size 1.27 1.27)
				)
				(justify left bottom)
				(hide yes)
			)
		)
		(pin "1"
		)
		(pin "2"
		)
		(instances
			(project "lpddr4-test-board"
				(path ""
					(reference "C107")
					(unit 1)
				)
			)
		)
	)
	(symbol
		(lib_id "antmicroCapacitors0402:C_10n_0402")
		(at 86.36 245.11 270)
		(unit 1)
		(exclude_from_sim no)
		(in_bom yes)
		(on_board yes)
		(dnp no)
		(property "Reference" "C112"
			(at 86.995 247.015 90)
			(effects
				(font
					(size 1.27 1.27)
					(thickness 0.15)
				)
				(justify left bottom)
			)
		)
		(property "Value" "C_10n_0402"
			(at 76.2 265.43 0)
			(effects
				(font
					(size 1.27 1.27)
					(thickness 0.15)
				)
				(justify left bottom)
				(hide yes)
			)
		)
		(property "Footprint" "antmicro-footprints:C_0402_1005Metric"
			(at 73.66 265.43 0)
			(effects
				(font
					(size 1.27 1.27)
					(thickness 0.15)
				)
				(justify left bottom)
				(hide yes)
			)
		)
		(property "Datasheet" "https://search.murata.co.jp/Ceramy/image/img/A01X/G101/ENG/GRM155R71H103KA88-01.pdf"
			(at 71.12 265.43 0)
			(effects
				(font
					(size 1.27 1.27)
					(thickness 0.15)
				)
				(justify left bottom)
				(hide yes)
			)
		)
		(property "Description" ""
			(at 86.36 245.11 0)
			(effects
				(font
					(size 1.27 1.27)
				)
			)
		)
		(property "Manufacturer" "Murata"
			(at 66.04 265.43 0)
			(effects
				(font
					(size 1.27 1.27)
					(thickness 0.15)
				)
				(justify left bottom)
				(hide yes)
			)
		)
		(property "MPN" "GRM155R71H103KA88D"
			(at 68.58 265.43 0)
			(effects
				(font
					(size 1.27 1.27)
					(thickness 0.15)
				)
				(justify left bottom)
				(hide yes)
			)
		)
		(property "Val" "10n"
			(at 86.995 250.825 90)
			(effects
				(font
					(size 1.27 1.27)
					(thickness 0.15)
				)
				(justify left bottom)
			)
		)
		(property "License" "Apache-2.0"
			(at 63.5 265.43 0)
			(effects
				(font
					(size 1.27 1.27)
					(thickness 0.15)
				)
				(justify left bottom)
				(hide yes)
			)
		)
		(property "Author" "Antmicro"
			(at 60.96 265.43 0)
			(effects
				(font
					(size 1.27 1.27)
					(thickness 0.15)
				)
				(justify left bottom)
				(hide yes)
			)
		)
		(property "Voltage" "50V"
			(at 58.42 265.43 0)
			(effects
				(font
					(size 1.27 1.27)
				)
				(justify left bottom)
				(hide yes)
			)
		)
		(property "Dielectric" "X7R"
			(at 55.88 265.43 0)
			(effects
				(font
					(size 1.27 1.27)
				)
				(justify left bottom)
				(hide yes)
			)
		)
		(pin "1"
		)
		(pin "2"
		)
		(instances
			(project "lpddr4-test-board"
				(path ""
					(reference "C112")
					(unit 1)
				)
			)
		)
	)
	(symbol
		(lib_id "antmicroCapacitors0402:C_10n_0402")
		(at 85.09 81.28 270)
		(unit 1)
		(exclude_from_sim no)
		(in_bom yes)
		(on_board yes)
		(dnp no)
		(property "Reference" "C119"
			(at 85.725 83.185 90)
			(effects
				(font
					(size 1.27 1.27)
					(thickness 0.15)
				)
				(justify left bottom)
			)
		)
		(property "Value" "C_10n_0402"
			(at 74.93 101.6 0)
			(effects
				(font
					(size 1.27 1.27)
					(thickness 0.15)
				)
				(justify left bottom)
				(hide yes)
			)
		)
		(property "Footprint" "antmicro-footprints:C_0402_1005Metric"
			(at 72.39 101.6 0)
			(effects
				(font
					(size 1.27 1.27)
					(thickness 0.15)
				)
				(justify left bottom)
				(hide yes)
			)
		)
		(property "Datasheet" "https://search.murata.co.jp/Ceramy/image/img/A01X/G101/ENG/GRM155R71H103KA88-01.pdf"
			(at 69.85 101.6 0)
			(effects
				(font
					(size 1.27 1.27)
					(thickness 0.15)
				)
				(justify left bottom)
				(hide yes)
			)
		)
		(property "Description" ""
			(at 85.09 81.28 0)
			(effects
				(font
					(size 1.27 1.27)
				)
			)
		)
		(property "Manufacturer" "Murata"
			(at 64.77 101.6 0)
			(effects
				(font
					(size 1.27 1.27)
					(thickness 0.15)
				)
				(justify left bottom)
				(hide yes)
			)
		)
		(property "MPN" "GRM155R71H103KA88D"
			(at 67.31 101.6 0)
			(effects
				(font
					(size 1.27 1.27)
					(thickness 0.15)
				)
				(justify left bottom)
				(hide yes)
			)
		)
		(property "Val" "10n"
			(at 85.725 86.995 90)
			(effects
				(font
					(size 1.27 1.27)
					(thickness 0.15)
				)
				(justify left bottom)
			)
		)
		(property "License" "Apache-2.0"
			(at 62.23 101.6 0)
			(effects
				(font
					(size 1.27 1.27)
					(thickness 0.15)
				)
				(justify left bottom)
				(hide yes)
			)
		)
		(property "Author" "Antmicro"
			(at 59.69 101.6 0)
			(effects
				(font
					(size 1.27 1.27)
					(thickness 0.15)
				)
				(justify left bottom)
				(hide yes)
			)
		)
		(property "Voltage" "50V"
			(at 57.15 101.6 0)
			(effects
				(font
					(size 1.27 1.27)
				)
				(justify left bottom)
				(hide yes)
			)
		)
		(property "Dielectric" "X7R"
			(at 54.61 101.6 0)
			(effects
				(font
					(size 1.27 1.27)
				)
				(justify left bottom)
				(hide yes)
			)
		)
		(pin "1"
		)
		(pin "2"
		)
		(instances
			(project "lpddr4-test-board"
				(path ""
					(reference "C119")
					(unit 1)
				)
			)
		)
	)
	(symbol
		(lib_id "antmicroCapacitors0402:C_10n_0402")
		(at 92.075 81.28 270)
		(unit 1)
		(exclude_from_sim no)
		(in_bom yes)
		(on_board yes)
		(dnp no)
		(property "Reference" "C120"
			(at 92.71 83.185 90)
			(effects
				(font
					(size 1.27 1.27)
					(thickness 0.15)
				)
				(justify left bottom)
			)
		)
		(property "Value" "C_10n_0402"
			(at 81.915 101.6 0)
			(effects
				(font
					(size 1.27 1.27)
					(thickness 0.15)
				)
				(justify left bottom)
				(hide yes)
			)
		)
		(property "Footprint" "antmicro-footprints:C_0402_1005Metric"
			(at 79.375 101.6 0)
			(effects
				(font
					(size 1.27 1.27)
					(thickness 0.15)
				)
				(justify left bottom)
				(hide yes)
			)
		)
		(property "Datasheet" "https://search.murata.co.jp/Ceramy/image/img/A01X/G101/ENG/GRM155R71H103KA88-01.pdf"
			(at 76.835 101.6 0)
			(effects
				(font
					(size 1.27 1.27)
					(thickness 0.15)
				)
				(justify left bottom)
				(hide yes)
			)
		)
		(property "Description" ""
			(at 92.075 81.28 0)
			(effects
				(font
					(size 1.27 1.27)
				)
			)
		)
		(property "Manufacturer" "Murata"
			(at 71.755 101.6 0)
			(effects
				(font
					(size 1.27 1.27)
					(thickness 0.15)
				)
				(justify left bottom)
				(hide yes)
			)
		)
		(property "MPN" "GRM155R71H103KA88D"
			(at 74.295 101.6 0)
			(effects
				(font
					(size 1.27 1.27)
					(thickness 0.15)
				)
				(justify left bottom)
				(hide yes)
			)
		)
		(property "Val" "10n"
			(at 92.71 86.995 90)
			(effects
				(font
					(size 1.27 1.27)
					(thickness 0.15)
				)
				(justify left bottom)
			)
		)
		(property "License" "Apache-2.0"
			(at 69.215 101.6 0)
			(effects
				(font
					(size 1.27 1.27)
					(thickness 0.15)
				)
				(justify left bottom)
				(hide yes)
			)
		)
		(property "Author" "Antmicro"
			(at 66.675 101.6 0)
			(effects
				(font
					(size 1.27 1.27)
					(thickness 0.15)
				)
				(justify left bottom)
				(hide yes)
			)
		)
		(property "Voltage" "50V"
			(at 64.135 101.6 0)
			(effects
				(font
					(size 1.27 1.27)
				)
				(justify left bottom)
				(hide yes)
			)
		)
		(property "Dielectric" "X7R"
			(at 61.595 101.6 0)
			(effects
				(font
					(size 1.27 1.27)
				)
				(justify left bottom)
				(hide yes)
			)
		)
		(pin "1"
		)
		(pin "2"
		)
		(instances
			(project "lpddr4-test-board"
				(path ""
					(reference "C120")
					(unit 1)
				)
			)
		)
	)
	(symbol
		(lib_id "antmicroCapacitors0402:C_10n_0402")
		(at 71.12 81.28 270)
		(unit 1)
		(exclude_from_sim no)
		(in_bom yes)
		(on_board yes)
		(dnp no)
		(property "Reference" "C113"
			(at 71.755 83.185 90)
			(effects
				(font
					(size 1.27 1.27)
					(thickness 0.15)
				)
				(justify left bottom)
			)
		)
		(property "Value" "C_10n_0402"
			(at 60.96 101.6 0)
			(effects
				(font
					(size 1.27 1.27)
					(thickness 0.15)
				)
				(justify left bottom)
				(hide yes)
			)
		)
		(property "Footprint" "antmicro-footprints:C_0402_1005Metric"
			(at 58.42 101.6 0)
			(effects
				(font
					(size 1.27 1.27)
					(thickness 0.15)
				)
				(justify left bottom)
				(hide yes)
			)
		)
		(property "Datasheet" "https://search.murata.co.jp/Ceramy/image/img/A01X/G101/ENG/GRM155R71H103KA88-01.pdf"
			(at 55.88 101.6 0)
			(effects
				(font
					(size 1.27 1.27)
					(thickness 0.15)
				)
				(justify left bottom)
				(hide yes)
			)
		)
		(property "Description" ""
			(at 71.12 81.28 0)
			(effects
				(font
					(size 1.27 1.27)
				)
			)
		)
		(property "Manufacturer" "Murata"
			(at 50.8 101.6 0)
			(effects
				(font
					(size 1.27 1.27)
					(thickness 0.15)
				)
				(justify left bottom)
				(hide yes)
			)
		)
		(property "MPN" "GRM155R71H103KA88D"
			(at 53.34 101.6 0)
			(effects
				(font
					(size 1.27 1.27)
					(thickness 0.15)
				)
				(justify left bottom)
				(hide yes)
			)
		)
		(property "Val" "10n"
			(at 71.755 86.995 90)
			(effects
				(font
					(size 1.27 1.27)
					(thickness 0.15)
				)
				(justify left bottom)
			)
		)
		(property "License" "Apache-2.0"
			(at 48.26 101.6 0)
			(effects
				(font
					(size 1.27 1.27)
					(thickness 0.15)
				)
				(justify left bottom)
				(hide yes)
			)
		)
		(property "Author" "Antmicro"
			(at 45.72 101.6 0)
			(effects
				(font
					(size 1.27 1.27)
					(thickness 0.15)
				)
				(justify left bottom)
				(hide yes)
			)
		)
		(property "Voltage" "50V"
			(at 43.18 101.6 0)
			(effects
				(font
					(size 1.27 1.27)
				)
				(justify left bottom)
				(hide yes)
			)
		)
		(property "Dielectric" "X7R"
			(at 40.64 101.6 0)
			(effects
				(font
					(size 1.27 1.27)
				)
				(justify left bottom)
				(hide yes)
			)
		)
		(pin "1"
		)
		(pin "2"
		)
		(instances
			(project "lpddr4-test-board"
				(path ""
					(reference "C113")
					(unit 1)
				)
			)
		)
	)
	(symbol
		(lib_id "antmicroCapacitors0402:C_10n_0402")
		(at 78.105 81.28 270)
		(unit 1)
		(exclude_from_sim no)
		(in_bom yes)
		(on_board yes)
		(dnp no)
		(property "Reference" "C116"
			(at 78.74 83.185 90)
			(effects
				(font
					(size 1.27 1.27)
					(thickness 0.15)
				)
				(justify left bottom)
			)
		)
		(property "Value" "C_10n_0402"
			(at 67.945 101.6 0)
			(effects
				(font
					(size 1.27 1.27)
					(thickness 0.15)
				)
				(justify left bottom)
				(hide yes)
			)
		)
		(property "Footprint" "antmicro-footprints:C_0402_1005Metric"
			(at 65.405 101.6 0)
			(effects
				(font
					(size 1.27 1.27)
					(thickness 0.15)
				)
				(justify left bottom)
				(hide yes)
			)
		)
		(property "Datasheet" "https://search.murata.co.jp/Ceramy/image/img/A01X/G101/ENG/GRM155R71H103KA88-01.pdf"
			(at 62.865 101.6 0)
			(effects
				(font
					(size 1.27 1.27)
					(thickness 0.15)
				)
				(justify left bottom)
				(hide yes)
			)
		)
		(property "Description" ""
			(at 78.105 81.28 0)
			(effects
				(font
					(size 1.27 1.27)
				)
			)
		)
		(property "Manufacturer" "Murata"
			(at 57.785 101.6 0)
			(effects
				(font
					(size 1.27 1.27)
					(thickness 0.15)
				)
				(justify left bottom)
				(hide yes)
			)
		)
		(property "MPN" "GRM155R71H103KA88D"
			(at 60.325 101.6 0)
			(effects
				(font
					(size 1.27 1.27)
					(thickness 0.15)
				)
				(justify left bottom)
				(hide yes)
			)
		)
		(property "Val" "10n"
			(at 78.74 86.995 90)
			(effects
				(font
					(size 1.27 1.27)
					(thickness 0.15)
				)
				(justify left bottom)
			)
		)
		(property "License" "Apache-2.0"
			(at 55.245 101.6 0)
			(effects
				(font
					(size 1.27 1.27)
					(thickness 0.15)
				)
				(justify left bottom)
				(hide yes)
			)
		)
		(property "Author" "Antmicro"
			(at 52.705 101.6 0)
			(effects
				(font
					(size 1.27 1.27)
					(thickness 0.15)
				)
				(justify left bottom)
				(hide yes)
			)
		)
		(property "Voltage" "50V"
			(at 50.165 101.6 0)
			(effects
				(font
					(size 1.27 1.27)
				)
				(justify left bottom)
				(hide yes)
			)
		)
		(property "Dielectric" "X7R"
			(at 47.625 101.6 0)
			(effects
				(font
					(size 1.27 1.27)
				)
				(justify left bottom)
				(hide yes)
			)
		)
		(pin "1"
		)
		(pin "2"
		)
		(instances
			(project "lpddr4-test-board"
				(path ""
					(reference "C116")
					(unit 1)
				)
			)
		)
	)
	(symbol
		(lib_id "antmicroCapacitors0402:C_4u7_0402")
		(at 70.485 120.65 270)
		(unit 1)
		(exclude_from_sim no)
		(in_bom yes)
		(on_board yes)
		(dnp no)
		(property "Reference" "C115"
			(at 71.12 122.555 90)
			(effects
				(font
					(size 1.27 1.27)
					(thickness 0.15)
				)
				(justify left bottom)
			)
		)
		(property "Value" "C_4u7_0402"
			(at 60.325 140.97 0)
			(effects
				(font
					(size 1.27 1.27)
					(thickness 0.15)
				)
				(justify left bottom)
				(hide yes)
			)
		)
		(property "Footprint" "antmicro-footprints:C_0402_1005Metric"
			(at 57.785 140.97 0)
			(effects
				(font
					(size 1.27 1.27)
					(thickness 0.15)
				)
				(justify left bottom)
				(hide yes)
			)
		)
		(property "Datasheet" " "
			(at 55.245 140.97 0)
			(effects
				(font
					(size 1.27 1.27)
					(thickness 0.15)
				)
				(justify left bottom)
				(hide yes)
			)
		)
		(property "Description" ""
			(at 70.485 120.65 0)
			(effects
				(font
					(size 1.27 1.27)
				)
			)
		)
		(property "Manufacturer" "Murata"
			(at 50.165 140.97 0)
			(effects
				(font
					(size 1.27 1.27)
					(thickness 0.15)
				)
				(justify left bottom)
				(hide yes)
			)
		)
		(property "MPN" "GRM155R61A475MEAAD"
			(at 52.705 140.97 0)
			(effects
				(font
					(size 1.27 1.27)
					(thickness 0.15)
				)
				(justify left bottom)
				(hide yes)
			)
		)
		(property "Val" "4u7"
			(at 71.12 126.365 90)
			(effects
				(font
					(size 1.27 1.27)
					(thickness 0.15)
				)
				(justify left bottom)
			)
		)
		(property "License" "Apache-2.0"
			(at 47.625 140.97 0)
			(effects
				(font
					(size 1.27 1.27)
					(thickness 0.15)
				)
				(justify left bottom)
				(hide yes)
			)
		)
		(property "Author" "Antmicro"
			(at 45.085 140.97 0)
			(effects
				(font
					(size 1.27 1.27)
					(thickness 0.15)
				)
				(justify left bottom)
				(hide yes)
			)
		)
		(property "Voltage" ""
			(at 42.545 140.97 0)
			(effects
				(font
					(size 1.27 1.27)
				)
				(justify left bottom)
				(hide yes)
			)
		)
		(property "Dielectric" ""
			(at 40.005 140.97 0)
			(effects
				(font
					(size 1.27 1.27)
				)
				(justify left bottom)
				(hide yes)
			)
		)
		(pin "1"
		)
		(pin "2"
		)
		(instances
			(project "lpddr4-test-board"
				(path ""
					(reference "C115")
					(unit 1)
				)
			)
		)
	)
	(symbol
		(lib_id "antmicroCapacitors0402:C_470n_0402")
		(at 64.135 81.28 270)
		(unit 1)
		(exclude_from_sim no)
		(in_bom yes)
		(on_board yes)
		(dnp no)
		(property "Reference" "C108"
			(at 64.77 83.185 90)
			(effects
				(font
					(size 1.27 1.27)
					(thickness 0.15)
				)
				(justify left bottom)
			)
		)
		(property "Value" "C_470n_0402"
			(at 53.975 101.6 0)
			(effects
				(font
					(size 1.27 1.27)
					(thickness 0.15)
				)
				(justify left bottom)
				(hide yes)
			)
		)
		(property "Footprint" "antmicro-footprints:C_0402_1005Metric"
			(at 51.435 101.6 0)
			(effects
				(font
					(size 1.27 1.27)
					(thickness 0.15)
				)
				(justify left bottom)
				(hide yes)
			)
		)
		(property "Datasheet" " "
			(at 48.895 101.6 0)
			(effects
				(font
					(size 1.27 1.27)
					(thickness 0.15)
				)
				(justify left bottom)
				(hide yes)
			)
		)
		(property "Description" ""
			(at 64.135 81.28 0)
			(effects
				(font
					(size 1.27 1.27)
				)
			)
		)
		(property "Manufacturer" "TDK"
			(at 43.815 101.6 0)
			(effects
				(font
					(size 1.27 1.27)
					(thickness 0.15)
				)
				(justify left bottom)
				(hide yes)
			)
		)
		(property "MPN" "C1005X5R1E474M050BB"
			(at 46.355 101.6 0)
			(effects
				(font
					(size 1.27 1.27)
					(thickness 0.15)
				)
				(justify left bottom)
				(hide yes)
			)
		)
		(property "Val" "470n"
			(at 64.77 86.995 90)
			(effects
				(font
					(size 1.27 1.27)
					(thickness 0.15)
				)
				(justify left bottom)
			)
		)
		(property "License" "Apache-2.0"
			(at 41.275 101.6 0)
			(effects
				(font
					(size 1.27 1.27)
					(thickness 0.15)
				)
				(justify left bottom)
				(hide yes)
			)
		)
		(property "Author" "Antmicro"
			(at 38.735 101.6 0)
			(effects
				(font
					(size 1.27 1.27)
					(thickness 0.15)
				)
				(justify left bottom)
				(hide yes)
			)
		)
		(property "Voltage" ""
			(at 36.195 101.6 0)
			(effects
				(font
					(size 1.27 1.27)
				)
				(justify left bottom)
				(hide yes)
			)
		)
		(property "Dielectric" ""
			(at 33.655 101.6 0)
			(effects
				(font
					(size 1.27 1.27)
				)
				(justify left bottom)
				(hide yes)
			)
		)
		(pin "1"
		)
		(pin "2"
		)
		(instances
			(project "lpddr4-test-board"
				(path ""
					(reference "C108")
					(unit 1)
				)
			)
		)
	)
	(symbol
		(lib_id "antmicroCapacitors0402:C_4u7_0402")
		(at 36.195 81.28 270)
		(unit 1)
		(exclude_from_sim no)
		(in_bom yes)
		(on_board yes)
		(dnp no)
		(property "Reference" "C97"
			(at 36.83 83.185 90)
			(effects
				(font
					(size 1.27 1.27)
					(thickness 0.15)
				)
				(justify left bottom)
			)
		)
		(property "Value" "C_4u7_0402"
			(at 26.035 101.6 0)
			(effects
				(font
					(size 1.27 1.27)
					(thickness 0.15)
				)
				(justify left bottom)
				(hide yes)
			)
		)
		(property "Footprint" "antmicro-footprints:C_0402_1005Metric"
			(at 23.495 101.6 0)
			(effects
				(font
					(size 1.27 1.27)
					(thickness 0.15)
				)
				(justify left bottom)
				(hide yes)
			)
		)
		(property "Datasheet" " "
			(at 20.955 101.6 0)
			(effects
				(font
					(size 1.27 1.27)
					(thickness 0.15)
				)
				(justify left bottom)
				(hide yes)
			)
		)
		(property "Description" ""
			(at 36.195 81.28 0)
			(effects
				(font
					(size 1.27 1.27)
				)
			)
		)
		(property "Manufacturer" "Murata"
			(at 15.875 101.6 0)
			(effects
				(font
					(size 1.27 1.27)
					(thickness 0.15)
				)
				(justify left bottom)
				(hide yes)
			)
		)
		(property "MPN" "GRM155R61A475MEAAD"
			(at 18.415 101.6 0)
			(effects
				(font
					(size 1.27 1.27)
					(thickness 0.15)
				)
				(justify left bottom)
				(hide yes)
			)
		)
		(property "Val" "4u7"
			(at 36.83 86.995 90)
			(effects
				(font
					(size 1.27 1.27)
					(thickness 0.15)
				)
				(justify left bottom)
			)
		)
		(property "License" "Apache-2.0"
			(at 13.335 101.6 0)
			(effects
				(font
					(size 1.27 1.27)
					(thickness 0.15)
				)
				(justify left bottom)
				(hide yes)
			)
		)
		(property "Author" "Antmicro"
			(at 10.795 101.6 0)
			(effects
				(font
					(size 1.27 1.27)
					(thickness 0.15)
				)
				(justify left bottom)
				(hide yes)
			)
		)
		(property "Voltage" ""
			(at 8.255 101.6 0)
			(effects
				(font
					(size 1.27 1.27)
				)
				(justify left bottom)
				(hide yes)
			)
		)
		(property "Dielectric" ""
			(at 5.715 101.6 0)
			(effects
				(font
					(size 1.27 1.27)
				)
				(justify left bottom)
				(hide yes)
			)
		)
		(pin "1"
		)
		(pin "2"
		)
		(instances
			(project "lpddr4-test-board"
				(path ""
					(reference "C97")
					(unit 1)
				)
			)
		)
	)
	(symbol
		(lib_id "antmicroCapacitors0402:C_470n_0402")
		(at 43.18 81.28 270)
		(unit 1)
		(exclude_from_sim no)
		(in_bom yes)
		(on_board yes)
		(dnp no)
		(property "Reference" "C98"
			(at 43.815 83.185 90)
			(effects
				(font
					(size 1.27 1.27)
					(thickness 0.15)
				)
				(justify left bottom)
			)
		)
		(property "Value" "C_470n_0402"
			(at 33.02 101.6 0)
			(effects
				(font
					(size 1.27 1.27)
					(thickness 0.15)
				)
				(justify left bottom)
				(hide yes)
			)
		)
		(property "Footprint" "antmicro-footprints:C_0402_1005Metric"
			(at 30.48 101.6 0)
			(effects
				(font
					(size 1.27 1.27)
					(thickness 0.15)
				)
				(justify left bottom)
				(hide yes)
			)
		)
		(property "Datasheet" " "
			(at 27.94 101.6 0)
			(effects
				(font
					(size 1.27 1.27)
					(thickness 0.15)
				)
				(justify left bottom)
				(hide yes)
			)
		)
		(property "Description" ""
			(at 43.18 81.28 0)
			(effects
				(font
					(size 1.27 1.27)
				)
			)
		)
		(property "Manufacturer" "TDK"
			(at 22.86 101.6 0)
			(effects
				(font
					(size 1.27 1.27)
					(thickness 0.15)
				)
				(justify left bottom)
				(hide yes)
			)
		)
		(property "MPN" "C1005X5R1E474M050BB"
			(at 25.4 101.6 0)
			(effects
				(font
					(size 1.27 1.27)
					(thickness 0.15)
				)
				(justify left bottom)
				(hide yes)
			)
		)
		(property "Val" "470n"
			(at 43.815 86.995 90)
			(effects
				(font
					(size 1.27 1.27)
					(thickness 0.15)
				)
				(justify left bottom)
			)
		)
		(property "License" "Apache-2.0"
			(at 20.32 101.6 0)
			(effects
				(font
					(size 1.27 1.27)
					(thickness 0.15)
				)
				(justify left bottom)
				(hide yes)
			)
		)
		(property "Author" "Antmicro"
			(at 17.78 101.6 0)
			(effects
				(font
					(size 1.27 1.27)
					(thickness 0.15)
				)
				(justify left bottom)
				(hide yes)
			)
		)
		(property "Voltage" ""
			(at 15.24 101.6 0)
			(effects
				(font
					(size 1.27 1.27)
				)
				(justify left bottom)
				(hide yes)
			)
		)
		(property "Dielectric" ""
			(at 12.7 101.6 0)
			(effects
				(font
					(size 1.27 1.27)
				)
				(justify left bottom)
				(hide yes)
			)
		)
		(pin "1"
		)
		(pin "2"
		)
		(instances
			(project "lpddr4-test-board"
				(path ""
					(reference "C98")
					(unit 1)
				)
			)
		)
	)
	(symbol
		(lib_id "antmicroCapacitors0402:C_470n_0402")
		(at 50.165 81.28 270)
		(unit 1)
		(exclude_from_sim no)
		(in_bom yes)
		(on_board yes)
		(dnp no)
		(property "Reference" "C100"
			(at 50.8 83.185 90)
			(effects
				(font
					(size 1.27 1.27)
					(thickness 0.15)
				)
				(justify left bottom)
			)
		)
		(property "Value" "C_470n_0402"
			(at 40.005 101.6 0)
			(effects
				(font
					(size 1.27 1.27)
					(thickness 0.15)
				)
				(justify left bottom)
				(hide yes)
			)
		)
		(property "Footprint" "antmicro-footprints:C_0402_1005Metric"
			(at 37.465 101.6 0)
			(effects
				(font
					(size 1.27 1.27)
					(thickness 0.15)
				)
				(justify left bottom)
				(hide yes)
			)
		)
		(property "Datasheet" " "
			(at 34.925 101.6 0)
			(effects
				(font
					(size 1.27 1.27)
					(thickness 0.15)
				)
				(justify left bottom)
				(hide yes)
			)
		)
		(property "Description" ""
			(at 50.165 81.28 0)
			(effects
				(font
					(size 1.27 1.27)
				)
			)
		)
		(property "Manufacturer" "TDK"
			(at 29.845 101.6 0)
			(effects
				(font
					(size 1.27 1.27)
					(thickness 0.15)
				)
				(justify left bottom)
				(hide yes)
			)
		)
		(property "MPN" "C1005X5R1E474M050BB"
			(at 32.385 101.6 0)
			(effects
				(font
					(size 1.27 1.27)
					(thickness 0.15)
				)
				(justify left bottom)
				(hide yes)
			)
		)
		(property "Val" "470n"
			(at 50.8 86.995 90)
			(effects
				(font
					(size 1.27 1.27)
					(thickness 0.15)
				)
				(justify left bottom)
			)
		)
		(property "License" "Apache-2.0"
			(at 27.305 101.6 0)
			(effects
				(font
					(size 1.27 1.27)
					(thickness 0.15)
				)
				(justify left bottom)
				(hide yes)
			)
		)
		(property "Author" "Antmicro"
			(at 24.765 101.6 0)
			(effects
				(font
					(size 1.27 1.27)
					(thickness 0.15)
				)
				(justify left bottom)
				(hide yes)
			)
		)
		(property "Voltage" ""
			(at 22.225 101.6 0)
			(effects
				(font
					(size 1.27 1.27)
				)
				(justify left bottom)
				(hide yes)
			)
		)
		(property "Dielectric" ""
			(at 19.685 101.6 0)
			(effects
				(font
					(size 1.27 1.27)
				)
				(justify left bottom)
				(hide yes)
			)
		)
		(pin "1"
		)
		(pin "2"
		)
		(instances
			(project "lpddr4-test-board"
				(path ""
					(reference "C100")
					(unit 1)
				)
			)
		)
	)
	(symbol
		(lib_id "antmicroCapacitors0402:C_470n_0402")
		(at 57.15 81.28 270)
		(unit 1)
		(exclude_from_sim no)
		(in_bom yes)
		(on_board yes)
		(dnp no)
		(property "Reference" "C104"
			(at 57.785 83.185 90)
			(effects
				(font
					(size 1.27 1.27)
					(thickness 0.15)
				)
				(justify left bottom)
			)
		)
		(property "Value" "C_470n_0402"
			(at 46.99 101.6 0)
			(effects
				(font
					(size 1.27 1.27)
					(thickness 0.15)
				)
				(justify left bottom)
				(hide yes)
			)
		)
		(property "Footprint" "antmicro-footprints:C_0402_1005Metric"
			(at 44.45 101.6 0)
			(effects
				(font
					(size 1.27 1.27)
					(thickness 0.15)
				)
				(justify left bottom)
				(hide yes)
			)
		)
		(property "Datasheet" " "
			(at 41.91 101.6 0)
			(effects
				(font
					(size 1.27 1.27)
					(thickness 0.15)
				)
				(justify left bottom)
				(hide yes)
			)
		)
		(property "Description" ""
			(at 57.15 81.28 0)
			(effects
				(font
					(size 1.27 1.27)
				)
			)
		)
		(property "Manufacturer" "TDK"
			(at 36.83 101.6 0)
			(effects
				(font
					(size 1.27 1.27)
					(thickness 0.15)
				)
				(justify left bottom)
				(hide yes)
			)
		)
		(property "MPN" "C1005X5R1E474M050BB"
			(at 39.37 101.6 0)
			(effects
				(font
					(size 1.27 1.27)
					(thickness 0.15)
				)
				(justify left bottom)
				(hide yes)
			)
		)
		(property "Val" "470n"
			(at 57.785 86.995 90)
			(effects
				(font
					(size 1.27 1.27)
					(thickness 0.15)
				)
				(justify left bottom)
			)
		)
		(property "License" "Apache-2.0"
			(at 34.29 101.6 0)
			(effects
				(font
					(size 1.27 1.27)
					(thickness 0.15)
				)
				(justify left bottom)
				(hide yes)
			)
		)
		(property "Author" "Antmicro"
			(at 31.75 101.6 0)
			(effects
				(font
					(size 1.27 1.27)
					(thickness 0.15)
				)
				(justify left bottom)
				(hide yes)
			)
		)
		(property "Voltage" ""
			(at 29.21 101.6 0)
			(effects
				(font
					(size 1.27 1.27)
				)
				(justify left bottom)
				(hide yes)
			)
		)
		(property "Dielectric" ""
			(at 26.67 101.6 0)
			(effects
				(font
					(size 1.27 1.27)
				)
				(justify left bottom)
				(hide yes)
			)
		)
		(pin "1"
		)
		(pin "2"
		)
		(instances
			(project "lpddr4-test-board"
				(path ""
					(reference "C104")
					(unit 1)
				)
			)
		)
	)
	(symbol
		(lib_id "antmicroCapacitors0402:C_4u7_0402")
		(at 77.47 120.65 270)
		(unit 1)
		(exclude_from_sim no)
		(in_bom yes)
		(on_board yes)
		(dnp no)
		(property "Reference" "C118"
			(at 78.105 122.555 90)
			(effects
				(font
					(size 1.27 1.27)
					(thickness 0.15)
				)
				(justify left bottom)
			)
		)
		(property "Value" "C_4u7_0402"
			(at 67.31 140.97 0)
			(effects
				(font
					(size 1.27 1.27)
					(thickness 0.15)
				)
				(justify left bottom)
				(hide yes)
			)
		)
		(property "Footprint" "antmicro-footprints:C_0402_1005Metric"
			(at 64.77 140.97 0)
			(effects
				(font
					(size 1.27 1.27)
					(thickness 0.15)
				)
				(justify left bottom)
				(hide yes)
			)
		)
		(property "Datasheet" " "
			(at 62.23 140.97 0)
			(effects
				(font
					(size 1.27 1.27)
					(thickness 0.15)
				)
				(justify left bottom)
				(hide yes)
			)
		)
		(property "Description" ""
			(at 77.47 120.65 0)
			(effects
				(font
					(size 1.27 1.27)
				)
			)
		)
		(property "Manufacturer" "Murata"
			(at 57.15 140.97 0)
			(effects
				(font
					(size 1.27 1.27)
					(thickness 0.15)
				)
				(justify left bottom)
				(hide yes)
			)
		)
		(property "MPN" "GRM155R61A475MEAAD"
			(at 59.69 140.97 0)
			(effects
				(font
					(size 1.27 1.27)
					(thickness 0.15)
				)
				(justify left bottom)
				(hide yes)
			)
		)
		(property "Val" "4u7"
			(at 78.105 126.365 90)
			(effects
				(font
					(size 1.27 1.27)
					(thickness 0.15)
				)
				(justify left bottom)
			)
		)
		(property "License" "Apache-2.0"
			(at 54.61 140.97 0)
			(effects
				(font
					(size 1.27 1.27)
					(thickness 0.15)
				)
				(justify left bottom)
				(hide yes)
			)
		)
		(property "Author" "Antmicro"
			(at 52.07 140.97 0)
			(effects
				(font
					(size 1.27 1.27)
					(thickness 0.15)
				)
				(justify left bottom)
				(hide yes)
			)
		)
		(property "Voltage" ""
			(at 49.53 140.97 0)
			(effects
				(font
					(size 1.27 1.27)
				)
				(justify left bottom)
				(hide yes)
			)
		)
		(property "Dielectric" ""
			(at 46.99 140.97 0)
			(effects
				(font
					(size 1.27 1.27)
				)
				(justify left bottom)
				(hide yes)
			)
		)
		(pin "1"
		)
		(pin "2"
		)
		(instances
			(project "lpddr4-test-board"
				(path ""
					(reference "C118")
					(unit 1)
				)
			)
		)
	)
	(symbol
		(lib_id "antmicroCapacitors0402:C_4u7_0402")
		(at 63.5 120.65 270)
		(unit 1)
		(exclude_from_sim no)
		(in_bom yes)
		(on_board yes)
		(dnp no)
		(property "Reference" "C110"
			(at 64.135 122.555 90)
			(effects
				(font
					(size 1.27 1.27)
					(thickness 0.15)
				)
				(justify left bottom)
			)
		)
		(property "Value" "C_4u7_0402"
			(at 53.34 140.97 0)
			(effects
				(font
					(size 1.27 1.27)
					(thickness 0.15)
				)
				(justify left bottom)
				(hide yes)
			)
		)
		(property "Footprint" "antmicro-footprints:C_0402_1005Metric"
			(at 50.8 140.97 0)
			(effects
				(font
					(size 1.27 1.27)
					(thickness 0.15)
				)
				(justify left bottom)
				(hide yes)
			)
		)
		(property "Datasheet" " "
			(at 48.26 140.97 0)
			(effects
				(font
					(size 1.27 1.27)
					(thickness 0.15)
				)
				(justify left bottom)
				(hide yes)
			)
		)
		(property "Description" ""
			(at 63.5 120.65 0)
			(effects
				(font
					(size 1.27 1.27)
				)
			)
		)
		(property "Manufacturer" "Murata"
			(at 43.18 140.97 0)
			(effects
				(font
					(size 1.27 1.27)
					(thickness 0.15)
				)
				(justify left bottom)
				(hide yes)
			)
		)
		(property "MPN" "GRM155R61A475MEAAD"
			(at 45.72 140.97 0)
			(effects
				(font
					(size 1.27 1.27)
					(thickness 0.15)
				)
				(justify left bottom)
				(hide yes)
			)
		)
		(property "Val" "4u7"
			(at 64.135 126.365 90)
			(effects
				(font
					(size 1.27 1.27)
					(thickness 0.15)
				)
				(justify left bottom)
			)
		)
		(property "License" "Apache-2.0"
			(at 40.64 140.97 0)
			(effects
				(font
					(size 1.27 1.27)
					(thickness 0.15)
				)
				(justify left bottom)
				(hide yes)
			)
		)
		(property "Author" "Antmicro"
			(at 38.1 140.97 0)
			(effects
				(font
					(size 1.27 1.27)
					(thickness 0.15)
				)
				(justify left bottom)
				(hide yes)
			)
		)
		(property "Voltage" ""
			(at 35.56 140.97 0)
			(effects
				(font
					(size 1.27 1.27)
				)
				(justify left bottom)
				(hide yes)
			)
		)
		(property "Dielectric" ""
			(at 33.02 140.97 0)
			(effects
				(font
					(size 1.27 1.27)
				)
				(justify left bottom)
				(hide yes)
			)
		)
		(pin "1"
		)
		(pin "2"
		)
		(instances
			(project "lpddr4-test-board"
				(path ""
					(reference "C110")
					(unit 1)
				)
			)
		)
	)
	(symbol
		(lib_id "antmicroCapacitors0402:C_4u7_0402")
		(at 56.515 154.94 270)
		(unit 1)
		(exclude_from_sim no)
		(in_bom yes)
		(on_board yes)
		(dnp no)
		(property "Reference" "C101"
			(at 57.15 156.845 90)
			(effects
				(font
					(size 1.27 1.27)
					(thickness 0.15)
				)
				(justify left bottom)
			)
		)
		(property "Value" "C_4u7_0402"
			(at 46.355 175.26 0)
			(effects
				(font
					(size 1.27 1.27)
					(thickness 0.15)
				)
				(justify left bottom)
				(hide yes)
			)
		)
		(property "Footprint" "antmicro-footprints:C_0402_1005Metric"
			(at 43.815 175.26 0)
			(effects
				(font
					(size 1.27 1.27)
					(thickness 0.15)
				)
				(justify left bottom)
				(hide yes)
			)
		)
		(property "Datasheet" " "
			(at 41.275 175.26 0)
			(effects
				(font
					(size 1.27 1.27)
					(thickness 0.15)
				)
				(justify left bottom)
				(hide yes)
			)
		)
		(property "Description" ""
			(at 56.515 154.94 0)
			(effects
				(font
					(size 1.27 1.27)
				)
			)
		)
		(property "Manufacturer" "Murata"
			(at 36.195 175.26 0)
			(effects
				(font
					(size 1.27 1.27)
					(thickness 0.15)
				)
				(justify left bottom)
				(hide yes)
			)
		)
		(property "MPN" "GRM155R61A475MEAAD"
			(at 38.735 175.26 0)
			(effects
				(font
					(size 1.27 1.27)
					(thickness 0.15)
				)
				(justify left bottom)
				(hide yes)
			)
		)
		(property "Val" "4u7"
			(at 57.15 160.655 90)
			(effects
				(font
					(size 1.27 1.27)
					(thickness 0.15)
				)
				(justify left bottom)
			)
		)
		(property "License" "Apache-2.0"
			(at 33.655 175.26 0)
			(effects
				(font
					(size 1.27 1.27)
					(thickness 0.15)
				)
				(justify left bottom)
				(hide yes)
			)
		)
		(property "Author" "Antmicro"
			(at 31.115 175.26 0)
			(effects
				(font
					(size 1.27 1.27)
					(thickness 0.15)
				)
				(justify left bottom)
				(hide yes)
			)
		)
		(property "Voltage" ""
			(at 28.575 175.26 0)
			(effects
				(font
					(size 1.27 1.27)
				)
				(justify left bottom)
				(hide yes)
			)
		)
		(property "Dielectric" ""
			(at 26.035 175.26 0)
			(effects
				(font
					(size 1.27 1.27)
				)
				(justify left bottom)
				(hide yes)
			)
		)
		(pin "1"
		)
		(pin "2"
		)
		(instances
			(project "lpddr4-test-board"
				(path ""
					(reference "C101")
					(unit 1)
				)
			)
		)
	)
	(symbol
		(lib_id "antmicroCapacitors0402:C_470n_0402")
		(at 63.5 154.94 270)
		(unit 1)
		(exclude_from_sim no)
		(in_bom yes)
		(on_board yes)
		(dnp no)
		(property "Reference" "C105"
			(at 64.135 156.845 90)
			(effects
				(font
					(size 1.27 1.27)
					(thickness 0.15)
				)
				(justify left bottom)
			)
		)
		(property "Value" "C_470n_0402"
			(at 53.34 175.26 0)
			(effects
				(font
					(size 1.27 1.27)
					(thickness 0.15)
				)
				(justify left bottom)
				(hide yes)
			)
		)
		(property "Footprint" "antmicro-footprints:C_0402_1005Metric"
			(at 50.8 175.26 0)
			(effects
				(font
					(size 1.27 1.27)
					(thickness 0.15)
				)
				(justify left bottom)
				(hide yes)
			)
		)
		(property "Datasheet" " "
			(at 48.26 175.26 0)
			(effects
				(font
					(size 1.27 1.27)
					(thickness 0.15)
				)
				(justify left bottom)
				(hide yes)
			)
		)
		(property "Description" ""
			(at 63.5 154.94 0)
			(effects
				(font
					(size 1.27 1.27)
				)
			)
		)
		(property "Manufacturer" "TDK"
			(at 43.18 175.26 0)
			(effects
				(font
					(size 1.27 1.27)
					(thickness 0.15)
				)
				(justify left bottom)
				(hide yes)
			)
		)
		(property "MPN" "C1005X5R1E474M050BB"
			(at 45.72 175.26 0)
			(effects
				(font
					(size 1.27 1.27)
					(thickness 0.15)
				)
				(justify left bottom)
				(hide yes)
			)
		)
		(property "Val" "470n"
			(at 64.135 160.655 90)
			(effects
				(font
					(size 1.27 1.27)
					(thickness 0.15)
				)
				(justify left bottom)
			)
		)
		(property "License" "Apache-2.0"
			(at 40.64 175.26 0)
			(effects
				(font
					(size 1.27 1.27)
					(thickness 0.15)
				)
				(justify left bottom)
				(hide yes)
			)
		)
		(property "Author" "Antmicro"
			(at 38.1 175.26 0)
			(effects
				(font
					(size 1.27 1.27)
					(thickness 0.15)
				)
				(justify left bottom)
				(hide yes)
			)
		)
		(property "Voltage" ""
			(at 35.56 175.26 0)
			(effects
				(font
					(size 1.27 1.27)
				)
				(justify left bottom)
				(hide yes)
			)
		)
		(property "Dielectric" ""
			(at 33.02 175.26 0)
			(effects
				(font
					(size 1.27 1.27)
				)
				(justify left bottom)
				(hide yes)
			)
		)
		(pin "1"
		)
		(pin "2"
		)
		(instances
			(project "lpddr4-test-board"
				(path ""
					(reference "C105")
					(unit 1)
				)
			)
		)
	)
	(symbol
		(lib_id "antmicroCapacitors0402:C_10n_0402")
		(at 77.47 154.94 270)
		(unit 1)
		(exclude_from_sim no)
		(in_bom yes)
		(on_board yes)
		(dnp no)
		(property "Reference" "C114"
			(at 78.105 156.845 90)
			(effects
				(font
					(size 1.27 1.27)
					(thickness 0.15)
				)
				(justify left bottom)
			)
		)
		(property "Value" "C_10n_0402"
			(at 67.31 175.26 0)
			(effects
				(font
					(size 1.27 1.27)
					(thickness 0.15)
				)
				(justify left bottom)
				(hide yes)
			)
		)
		(property "Footprint" "antmicro-footprints:C_0402_1005Metric"
			(at 64.77 175.26 0)
			(effects
				(font
					(size 1.27 1.27)
					(thickness 0.15)
				)
				(justify left bottom)
				(hide yes)
			)
		)
		(property "Datasheet" "https://search.murata.co.jp/Ceramy/image/img/A01X/G101/ENG/GRM155R71H103KA88-01.pdf"
			(at 62.23 175.26 0)
			(effects
				(font
					(size 1.27 1.27)
					(thickness 0.15)
				)
				(justify left bottom)
				(hide yes)
			)
		)
		(property "Description" ""
			(at 77.47 154.94 0)
			(effects
				(font
					(size 1.27 1.27)
				)
			)
		)
		(property "Manufacturer" "Murata"
			(at 57.15 175.26 0)
			(effects
				(font
					(size 1.27 1.27)
					(thickness 0.15)
				)
				(justify left bottom)
				(hide yes)
			)
		)
		(property "MPN" "GRM155R71H103KA88D"
			(at 59.69 175.26 0)
			(effects
				(font
					(size 1.27 1.27)
					(thickness 0.15)
				)
				(justify left bottom)
				(hide yes)
			)
		)
		(property "Val" "10n"
			(at 78.105 160.655 90)
			(effects
				(font
					(size 1.27 1.27)
					(thickness 0.15)
				)
				(justify left bottom)
			)
		)
		(property "License" "Apache-2.0"
			(at 54.61 175.26 0)
			(effects
				(font
					(size 1.27 1.27)
					(thickness 0.15)
				)
				(justify left bottom)
				(hide yes)
			)
		)
		(property "Author" "Antmicro"
			(at 52.07 175.26 0)
			(effects
				(font
					(size 1.27 1.27)
					(thickness 0.15)
				)
				(justify left bottom)
				(hide yes)
			)
		)
		(property "Voltage" "50V"
			(at 49.53 175.26 0)
			(effects
				(font
					(size 1.27 1.27)
				)
				(justify left bottom)
				(hide yes)
			)
		)
		(property "Dielectric" "X7R"
			(at 46.99 175.26 0)
			(effects
				(font
					(size 1.27 1.27)
				)
				(justify left bottom)
				(hide yes)
			)
		)
		(pin "1"
		)
		(pin "2"
		)
		(instances
			(project "lpddr4-test-board"
				(path ""
					(reference "C114")
					(unit 1)
				)
			)
		)
	)
	(symbol
		(lib_id "antmicroCapacitors0402:C_10n_0402")
		(at 84.455 154.94 270)
		(unit 1)
		(exclude_from_sim no)
		(in_bom yes)
		(on_board yes)
		(dnp no)
		(property "Reference" "C117"
			(at 85.09 156.845 90)
			(effects
				(font
					(size 1.27 1.27)
					(thickness 0.15)
				)
				(justify left bottom)
			)
		)
		(property "Value" "C_10n_0402"
			(at 74.295 175.26 0)
			(effects
				(font
					(size 1.27 1.27)
					(thickness 0.15)
				)
				(justify left bottom)
				(hide yes)
			)
		)
		(property "Footprint" "antmicro-footprints:C_0402_1005Metric"
			(at 71.755 175.26 0)
			(effects
				(font
					(size 1.27 1.27)
					(thickness 0.15)
				)
				(justify left bottom)
				(hide yes)
			)
		)
		(property "Datasheet" "https://search.murata.co.jp/Ceramy/image/img/A01X/G101/ENG/GRM155R71H103KA88-01.pdf"
			(at 69.215 175.26 0)
			(effects
				(font
					(size 1.27 1.27)
					(thickness 0.15)
				)
				(justify left bottom)
				(hide yes)
			)
		)
		(property "Description" ""
			(at 84.455 154.94 0)
			(effects
				(font
					(size 1.27 1.27)
				)
			)
		)
		(property "Manufacturer" "Murata"
			(at 64.135 175.26 0)
			(effects
				(font
					(size 1.27 1.27)
					(thickness 0.15)
				)
				(justify left bottom)
				(hide yes)
			)
		)
		(property "MPN" "GRM155R71H103KA88D"
			(at 66.675 175.26 0)
			(effects
				(font
					(size 1.27 1.27)
					(thickness 0.15)
				)
				(justify left bottom)
				(hide yes)
			)
		)
		(property "Val" "10n"
			(at 85.09 160.655 90)
			(effects
				(font
					(size 1.27 1.27)
					(thickness 0.15)
				)
				(justify left bottom)
			)
		)
		(property "License" "Apache-2.0"
			(at 61.595 175.26 0)
			(effects
				(font
					(size 1.27 1.27)
					(thickness 0.15)
				)
				(justify left bottom)
				(hide yes)
			)
		)
		(property "Author" "Antmicro"
			(at 59.055 175.26 0)
			(effects
				(font
					(size 1.27 1.27)
					(thickness 0.15)
				)
				(justify left bottom)
				(hide yes)
			)
		)
		(property "Voltage" "50V"
			(at 56.515 175.26 0)
			(effects
				(font
					(size 1.27 1.27)
				)
				(justify left bottom)
				(hide yes)
			)
		)
		(property "Dielectric" "X7R"
			(at 53.975 175.26 0)
			(effects
				(font
					(size 1.27 1.27)
				)
				(justify left bottom)
				(hide yes)
			)
		)
		(pin "1"
		)
		(pin "2"
		)
		(instances
			(project "lpddr4-test-board"
				(path ""
					(reference "C117")
					(unit 1)
				)
			)
		)
	)
	(symbol
		(lib_id "antmicroCapacitors0402:C_10n_0402")
		(at 70.485 154.94 270)
		(unit 1)
		(exclude_from_sim no)
		(in_bom yes)
		(on_board yes)
		(dnp no)
		(property "Reference" "C109"
			(at 71.12 156.845 90)
			(effects
				(font
					(size 1.27 1.27)
					(thickness 0.15)
				)
				(justify left bottom)
			)
		)
		(property "Value" "C_10n_0402"
			(at 60.325 175.26 0)
			(effects
				(font
					(size 1.27 1.27)
					(thickness 0.15)
				)
				(justify left bottom)
				(hide yes)
			)
		)
		(property "Footprint" "antmicro-footprints:C_0402_1005Metric"
			(at 57.785 175.26 0)
			(effects
				(font
					(size 1.27 1.27)
					(thickness 0.15)
				)
				(justify left bottom)
				(hide yes)
			)
		)
		(property "Datasheet" "https://search.murata.co.jp/Ceramy/image/img/A01X/G101/ENG/GRM155R71H103KA88-01.pdf"
			(at 55.245 175.26 0)
			(effects
				(font
					(size 1.27 1.27)
					(thickness 0.15)
				)
				(justify left bottom)
				(hide yes)
			)
		)
		(property "Description" ""
			(at 70.485 154.94 0)
			(effects
				(font
					(size 1.27 1.27)
				)
			)
		)
		(property "Manufacturer" "Murata"
			(at 50.165 175.26 0)
			(effects
				(font
					(size 1.27 1.27)
					(thickness 0.15)
				)
				(justify left bottom)
				(hide yes)
			)
		)
		(property "MPN" "GRM155R71H103KA88D"
			(at 52.705 175.26 0)
			(effects
				(font
					(size 1.27 1.27)
					(thickness 0.15)
				)
				(justify left bottom)
				(hide yes)
			)
		)
		(property "Val" "10n"
			(at 71.12 160.655 90)
			(effects
				(font
					(size 1.27 1.27)
					(thickness 0.15)
				)
				(justify left bottom)
			)
		)
		(property "License" "Apache-2.0"
			(at 47.625 175.26 0)
			(effects
				(font
					(size 1.27 1.27)
					(thickness 0.15)
				)
				(justify left bottom)
				(hide yes)
			)
		)
		(property "Author" "Antmicro"
			(at 45.085 175.26 0)
			(effects
				(font
					(size 1.27 1.27)
					(thickness 0.15)
				)
				(justify left bottom)
				(hide yes)
			)
		)
		(property "Voltage" "50V"
			(at 42.545 175.26 0)
			(effects
				(font
					(size 1.27 1.27)
				)
				(justify left bottom)
				(hide yes)
			)
		)
		(property "Dielectric" "X7R"
			(at 40.005 175.26 0)
			(effects
				(font
					(size 1.27 1.27)
				)
				(justify left bottom)
				(hide yes)
			)
		)
		(pin "1"
		)
		(pin "2"
		)
		(instances
			(project "lpddr4-test-board"
				(path ""
					(reference "C109")
					(unit 1)
				)
			)
		)
	)
	(symbol
		(lib_id "antmicroFerriteBeadsandChips:FB_120Z_2A_Murata-BLM18PG_0603")
		(at 57.785 243.84 0)
		(unit 1)
		(exclude_from_sim no)
		(in_bom yes)
		(on_board yes)
		(dnp no)
		(property "Reference" "FB6"
			(at 59.69 238.76 0)
			(effects
				(font
					(size 1.27 1.27)
					(thickness 0.15)
				)
				(justify left bottom)
			)
		)
		(property "Value" "FB_120Z_2A_0603"
			(at 73.025 248.92 0)
			(effects
				(font
					(size 1.27 1.27)
					(thickness 0.15)
				)
				(justify left bottom)
				(hide yes)
			)
		)
		(property "Footprint" "antmicro-footprints:FB_0603_1608Metric"
			(at 73.025 251.46 0)
			(effects
				(font
					(size 1.27 1.27)
					(thickness 0.15)
				)
				(justify left bottom)
				(hide yes)
			)
		)
		(property "Datasheet" "https://www.murata.com/en-us/products/productdata/8796738650142/ENFA0003.pdf"
			(at 73.025 254 0)
			(effects
				(font
					(size 1.27 1.27)
					(thickness 0.15)
				)
				(justify left bottom)
				(hide yes)
			)
		)
		(property "Description" ""
			(at 57.785 243.84 0)
			(effects
				(font
					(size 1.27 1.27)
				)
			)
		)
		(property "MPN" "BLM18PG121SN1D"
			(at 52.705 241.3 0)
			(effects
				(font
					(size 1.27 1.27)
					(thickness 0.15)
				)
				(justify left bottom)
			)
		)
		(property "Manufacturer" "Murata"
			(at 73.025 259.08 0)
			(effects
				(font
					(size 1.27 1.27)
					(thickness 0.15)
				)
				(justify left bottom)
				(hide yes)
			)
		)
		(property "Author" "Antmicro"
			(at 73.025 261.62 0)
			(effects
				(font
					(size 1.27 1.27)
					(thickness 0.15)
				)
				(justify left bottom)
				(hide yes)
			)
		)
		(property "License" "Apache-2.0"
			(at 73.025 264.16 0)
			(effects
				(font
					(size 1.27 1.27)
					(thickness 0.15)
				)
				(justify left bottom)
				(hide yes)
			)
		)
		(pin "1"
		)
		(pin "2"
		)
		(instances
			(project "lpddr4-test-board"
				(path ""
					(reference "FB6")
					(unit 1)
				)
			)
		)
	)
	(symbol
		(lib_id "antmicroFerriteBeadsandChips:FB_120Z_2A_Murata-BLM18PG_0603")
		(at 55.88 119.38 0)
		(unit 1)
		(exclude_from_sim no)
		(in_bom yes)
		(on_board yes)
		(dnp no)
		(property "Reference" "FB4"
			(at 57.785 114.3 0)
			(effects
				(font
					(size 1.27 1.27)
					(thickness 0.15)
				)
				(justify left bottom)
			)
		)
		(property "Value" "FB_120Z_2A_0603"
			(at 71.12 124.46 0)
			(effects
				(font
					(size 1.27 1.27)
					(thickness 0.15)
				)
				(justify left bottom)
				(hide yes)
			)
		)
		(property "Footprint" "antmicro-footprints:FB_0603_1608Metric"
			(at 71.12 127 0)
			(effects
				(font
					(size 1.27 1.27)
					(thickness 0.15)
				)
				(justify left bottom)
				(hide yes)
			)
		)
		(property "Datasheet" "https://www.murata.com/en-us/products/productdata/8796738650142/ENFA0003.pdf"
			(at 71.12 129.54 0)
			(effects
				(font
					(size 1.27 1.27)
					(thickness 0.15)
				)
				(justify left bottom)
				(hide yes)
			)
		)
		(property "Description" ""
			(at 55.88 119.38 0)
			(effects
				(font
					(size 1.27 1.27)
				)
			)
		)
		(property "MPN" "BLM18PG121SN1D"
			(at 50.8 116.84 0)
			(effects
				(font
					(size 1.27 1.27)
					(thickness 0.15)
				)
				(justify left bottom)
			)
		)
		(property "Manufacturer" "Murata"
			(at 71.12 134.62 0)
			(effects
				(font
					(size 1.27 1.27)
					(thickness 0.15)
				)
				(justify left bottom)
				(hide yes)
			)
		)
		(property "Author" "Antmicro"
			(at 71.12 137.16 0)
			(effects
				(font
					(size 1.27 1.27)
					(thickness 0.15)
				)
				(justify left bottom)
				(hide yes)
			)
		)
		(property "License" "Apache-2.0"
			(at 71.12 139.7 0)
			(effects
				(font
					(size 1.27 1.27)
					(thickness 0.15)
				)
				(justify left bottom)
				(hide yes)
			)
		)
		(pin "1"
		)
		(pin "2"
		)
		(instances
			(project "lpddr4-test-board"
				(path ""
					(reference "FB4")
					(unit 1)
				)
			)
		)
	)
	(symbol
		(lib_id "antmicroFerriteBeadsandChips:FB_120Z_2A_Murata-BLM18PG_0603")
		(at 61.595 201.93 0)
		(unit 1)
		(exclude_from_sim no)
		(in_bom yes)
		(on_board yes)
		(dnp no)
		(property "Reference" "FB5"
			(at 63.5 196.85 0)
			(effects
				(font
					(size 1.27 1.27)
					(thickness 0.15)
				)
				(justify left bottom)
			)
		)
		(property "Value" "FB_120Z_2A_0603"
			(at 76.835 207.01 0)
			(effects
				(font
					(size 1.27 1.27)
					(thickness 0.15)
				)
				(justify left bottom)
				(hide yes)
			)
		)
		(property "Footprint" "antmicro-footprints:FB_0603_1608Metric"
			(at 76.835 209.55 0)
			(effects
				(font
					(size 1.27 1.27)
					(thickness 0.15)
				)
				(justify left bottom)
				(hide yes)
			)
		)
		(property "Datasheet" "https://www.murata.com/en-us/products/productdata/8796738650142/ENFA0003.pdf"
			(at 76.835 212.09 0)
			(effects
				(font
					(size 1.27 1.27)
					(thickness 0.15)
				)
				(justify left bottom)
				(hide yes)
			)
		)
		(property "Description" ""
			(at 61.595 201.93 0)
			(effects
				(font
					(size 1.27 1.27)
				)
			)
		)
		(property "MPN" "BLM18PG121SN1D"
			(at 56.515 199.39 0)
			(effects
				(font
					(size 1.27 1.27)
					(thickness 0.15)
				)
				(justify left bottom)
			)
		)
		(property "Manufacturer" "Murata"
			(at 76.835 217.17 0)
			(effects
				(font
					(size 1.27 1.27)
					(thickness 0.15)
				)
				(justify left bottom)
				(hide yes)
			)
		)
		(property "Author" "Antmicro"
			(at 76.835 219.71 0)
			(effects
				(font
					(size 1.27 1.27)
					(thickness 0.15)
				)
				(justify left bottom)
				(hide yes)
			)
		)
		(property "License" "Apache-2.0"
			(at 76.835 222.25 0)
			(effects
				(font
					(size 1.27 1.27)
					(thickness 0.15)
				)
				(justify left bottom)
				(hide yes)
			)
		)
		(pin "1"
		)
		(pin "2"
		)
		(instances
			(project "lpddr4-test-board"
				(path ""
					(reference "FB5")
					(unit 1)
				)
			)
		)
	)
	(symbol
		(lib_id "antmicroCapacitors0402:C_100n_16V_X7R_0402")
		(at 76.2 203.2 270)
		(unit 1)
		(exclude_from_sim no)
		(in_bom yes)
		(on_board yes)
		(dnp no)
		(property "Reference" "C106"
			(at 76.835 205.105 90)
			(effects
				(font
					(size 1.27 1.27)
					(thickness 0.15)
				)
				(justify left bottom)
			)
		)
		(property "Value" "C_100n_16V_X7R_0402"
			(at 66.04 223.52 0)
			(effects
				(font
					(size 1.27 1.27)
					(thickness 0.15)
				)
				(justify left bottom)
				(hide yes)
			)
		)
		(property "Footprint" "antmicro-footprints:C_0402_1005Metric"
			(at 50.8 218.44 0)
			(effects
				(font
					(size 1.27 1.27)
					(thickness 0.15)
				)
				(justify left bottom)
				(hide yes)
			)
		)
		(property "Datasheet" "https://www.kemet.com/en/us/capacitors/product/C0402C104J4RAC7411.html"
			(at 48.26 218.44 0)
			(effects
				(font
					(size 1.27 1.27)
					(thickness 0.15)
				)
				(justify left bottom)
				(hide yes)
			)
		)
		(property "Description" "SMD Multilayer Ceramic Capacitor, 100nF, 50V, 0402, ±5%, X7R"
			(at 43.18 218.44 0)
			(effects
				(font
					(size 1.27 1.27)
				)
				(justify left bottom)
				(hide yes)
			)
		)
		(property "Manufacturer" "KEMET"
			(at 60.96 218.44 0)
			(effects
				(font
					(size 1.27 1.27)
					(thickness 0.15)
				)
				(justify left bottom)
				(hide yes)
			)
		)
		(property "MPN" "C0402C104J4RAC7411"
			(at 45.72 218.44 0)
			(effects
				(font
					(size 1.27 1.27)
					(thickness 0.15)
				)
				(justify left bottom)
				(hide yes)
			)
		)
		(property "Val" "100n"
			(at 76.708 209.042 90)
			(effects
				(font
					(size 1.27 1.27)
					(thickness 0.15)
				)
				(justify left bottom)
			)
		)
		(property "License" "Apache-2.0"
			(at 58.42 218.44 0)
			(effects
				(font
					(size 1.27 1.27)
					(thickness 0.15)
				)
				(justify left bottom)
				(hide yes)
			)
		)
		(property "Author" "Antmicro"
			(at 55.88 218.44 0)
			(effects
				(font
					(size 1.27 1.27)
					(thickness 0.15)
				)
				(justify left bottom)
				(hide yes)
			)
		)
		(property "Voltage" "16V"
			(at 66.04 218.44 0)
			(effects
				(font
					(size 1.27 1.27)
					(thickness 0.15)
				)
				(justify left bottom)
				(hide yes)
			)
		)
		(property "Dielectric" "X7R"
			(at 63.5 218.44 0)
			(effects
				(font
					(size 1.27 1.27)
					(thickness 0.15)
				)
				(justify left bottom)
				(hide yes)
			)
		)
		(pin "1"
		)
		(pin "2"
		)
		(instances
			(project "lpddr4-test-board"
				(path ""
					(reference "C106")
					(unit 1)
				)
			)
		)
	)
	(symbol
		(lib_id "antmicroCapacitors0402:C_4u7_0402")
		(at 69.215 203.2 270)
		(unit 1)
		(exclude_from_sim no)
		(in_bom yes)
		(on_board yes)
		(dnp no)
		(property "Reference" "C102"
			(at 69.85 205.105 90)
			(effects
				(font
					(size 1.27 1.27)
					(thickness 0.15)
				)
				(justify left bottom)
			)
		)
		(property "Value" "C_4u7_0402"
			(at 59.055 223.52 0)
			(effects
				(font
					(size 1.27 1.27)
					(thickness 0.15)
				)
				(justify left bottom)
				(hide yes)
			)
		)
		(property "Footprint" "antmicro-footprints:C_0402_1005Metric"
			(at 56.515 223.52 0)
			(effects
				(font
					(size 1.27 1.27)
					(thickness 0.15)
				)
				(justify left bottom)
				(hide yes)
			)
		)
		(property "Datasheet" " "
			(at 53.975 223.52 0)
			(effects
				(font
					(size 1.27 1.27)
					(thickness 0.15)
				)
				(justify left bottom)
				(hide yes)
			)
		)
		(property "Description" ""
			(at 69.215 203.2 0)
			(effects
				(font
					(size 1.27 1.27)
				)
			)
		)
		(property "Manufacturer" "Murata"
			(at 48.895 223.52 0)
			(effects
				(font
					(size 1.27 1.27)
					(thickness 0.15)
				)
				(justify left bottom)
				(hide yes)
			)
		)
		(property "MPN" "GRM155R61A475MEAAD"
			(at 51.435 223.52 0)
			(effects
				(font
					(size 1.27 1.27)
					(thickness 0.15)
				)
				(justify left bottom)
				(hide yes)
			)
		)
		(property "Val" "4u7"
			(at 69.85 208.915 90)
			(effects
				(font
					(size 1.27 1.27)
					(thickness 0.15)
				)
				(justify left bottom)
			)
		)
		(property "License" "Apache-2.0"
			(at 46.355 223.52 0)
			(effects
				(font
					(size 1.27 1.27)
					(thickness 0.15)
				)
				(justify left bottom)
				(hide yes)
			)
		)
		(property "Author" "Antmicro"
			(at 43.815 223.52 0)
			(effects
				(font
					(size 1.27 1.27)
					(thickness 0.15)
				)
				(justify left bottom)
				(hide yes)
			)
		)
		(property "Voltage" ""
			(at 41.275 223.52 0)
			(effects
				(font
					(size 1.27 1.27)
				)
				(justify left bottom)
				(hide yes)
			)
		)
		(property "Dielectric" ""
			(at 38.735 223.52 0)
			(effects
				(font
					(size 1.27 1.27)
				)
				(justify left bottom)
				(hide yes)
			)
		)
		(pin "1"
		)
		(pin "2"
		)
		(instances
			(project "lpddr4-test-board"
				(path ""
					(reference "C102")
					(unit 1)
				)
			)
		)
	)
	(symbol
		(lib_id "antmicroCapacitors0402:C_10n_0402")
		(at 83.185 203.2 270)
		(unit 1)
		(exclude_from_sim no)
		(in_bom yes)
		(on_board yes)
		(dnp no)
		(property "Reference" "C111"
			(at 83.82 205.105 90)
			(effects
				(font
					(size 1.27 1.27)
					(thickness 0.15)
				)
				(justify left bottom)
			)
		)
		(property "Value" "C_10n_0402"
			(at 73.025 223.52 0)
			(effects
				(font
					(size 1.27 1.27)
					(thickness 0.15)
				)
				(justify left bottom)
				(hide yes)
			)
		)
		(property "Footprint" "antmicro-footprints:C_0402_1005Metric"
			(at 70.485 223.52 0)
			(effects
				(font
					(size 1.27 1.27)
					(thickness 0.15)
				)
				(justify left bottom)
				(hide yes)
			)
		)
		(property "Datasheet" "https://search.murata.co.jp/Ceramy/image/img/A01X/G101/ENG/GRM155R71H103KA88-01.pdf"
			(at 67.945 223.52 0)
			(effects
				(font
					(size 1.27 1.27)
					(thickness 0.15)
				)
				(justify left bottom)
				(hide yes)
			)
		)
		(property "Description" ""
			(at 83.185 203.2 0)
			(effects
				(font
					(size 1.27 1.27)
				)
			)
		)
		(property "Manufacturer" "Murata"
			(at 62.865 223.52 0)
			(effects
				(font
					(size 1.27 1.27)
					(thickness 0.15)
				)
				(justify left bottom)
				(hide yes)
			)
		)
		(property "MPN" "GRM155R71H103KA88D"
			(at 65.405 223.52 0)
			(effects
				(font
					(size 1.27 1.27)
					(thickness 0.15)
				)
				(justify left bottom)
				(hide yes)
			)
		)
		(property "Val" "10n"
			(at 83.82 208.915 90)
			(effects
				(font
					(size 1.27 1.27)
					(thickness 0.15)
				)
				(justify left bottom)
			)
		)
		(property "License" "Apache-2.0"
			(at 60.325 223.52 0)
			(effects
				(font
					(size 1.27 1.27)
					(thickness 0.15)
				)
				(justify left bottom)
				(hide yes)
			)
		)
		(property "Author" "Antmicro"
			(at 57.785 223.52 0)
			(effects
				(font
					(size 1.27 1.27)
					(thickness 0.15)
				)
				(justify left bottom)
				(hide yes)
			)
		)
		(property "Voltage" "50V"
			(at 55.245 223.52 0)
			(effects
				(font
					(size 1.27 1.27)
				)
				(justify left bottom)
				(hide yes)
			)
		)
		(property "Dielectric" "X7R"
			(at 52.705 223.52 0)
			(effects
				(font
					(size 1.27 1.27)
				)
				(justify left bottom)
				(hide yes)
			)
		)
		(pin "1"
		)
		(pin "2"
		)
		(instances
			(project "lpddr4-test-board"
				(path ""
					(reference "C111")
					(unit 1)
				)
			)
		)
	)
	(symbol
		(lib_id "antmicropower:GND")
		(at 36.195 87.63 0)
		(unit 1)
		(exclude_from_sim no)
		(in_bom yes)
		(on_board yes)
		(dnp no)
		(property "Reference" "#PWR0134"
			(at 45.085 90.17 0)
			(effects
				(font
					(size 1.27 1.27)
					(thickness 0.15)
				)
				(justify left bottom)
				(hide yes)
			)
		)
		(property "Value" "GND"
			(at 34.29 92.075 0)
			(effects
				(font
					(size 1.27 1.27)
					(thickness 0.15)
				)
				(justify left bottom)
			)
		)
		(property "Footprint" ""
			(at 45.085 95.25 0)
			(effects
				(font
					(size 1.27 1.27)
					(thickness 0.15)
				)
				(justify left bottom)
				(hide yes)
			)
		)
		(property "Datasheet" ""
			(at 45.085 100.33 0)
			(effects
				(font
					(size 1.27 1.27)
					(thickness 0.15)
				)
				(justify left bottom)
				(hide yes)
			)
		)
		(property "Description" ""
			(at 36.195 87.63 0)
			(effects
				(font
					(size 1.27 1.27)
				)
			)
		)
		(property "Author" "Antmicro"
			(at 45.085 95.25 0)
			(effects
				(font
					(size 1.27 1.27)
					(thickness 0.15)
				)
				(justify left bottom)
				(hide yes)
			)
		)
		(property "License" "Apache-2.0"
			(at 45.085 97.79 0)
			(effects
				(font
					(size 1.27 1.27)
					(thickness 0.15)
				)
				(justify left bottom)
				(hide yes)
			)
		)
		(pin "1"
		)
		(instances
			(project "lpddr4-test-board"
				(path ""
					(reference "#PWR0134")
					(unit 1)
				)
			)
		)
	)
	(symbol
		(lib_id "antmicroModularConnectorsJacksWithMagnetics:Bus_RJ45_7499111121A")
		(at 215.265 209.55 0)
		(unit 1)
		(exclude_from_sim no)
		(in_bom yes)
		(on_board yes)
		(dnp no)
		(property "Reference" "J5"
			(at 217.805 203.835 0)
			(effects
				(font
					(size 1.27 1.27)
					(thickness 0.15)
				)
				(justify left bottom)
			)
		)
		(property "Value" "Bus_RJ45_7499111121A"
			(at 217.805 206.375 0)
			(effects
				(font
					(size 1.27 1.27)
					(thickness 0.15)
				)
				(justify left bottom)
			)
		)
		(property "Footprint" "antmicro-footprints:RJ45_7499111121A_Horizontal"
			(at 257.175 214.63 0)
			(effects
				(font
					(size 1.27 1.27)
					(thickness 0.15)
				)
				(justify left bottom)
				(hide yes)
			)
		)
		(property "Datasheet" "https://www.we-online.com/components/products/datasheet/7499111121A.pdf"
			(at 257.175 217.17 0)
			(effects
				(font
					(size 1.27 1.27)
					(thickness 0.15)
				)
				(justify left bottom)
				(hide yes)
			)
		)
		(property "Description" ""
			(at 215.265 209.55 0)
			(effects
				(font
					(size 1.27 1.27)
				)
			)
		)
		(property "MPN" "7499111121A"
			(at 257.175 219.71 0)
			(effects
				(font
					(size 1.27 1.27)
					(thickness 0.15)
				)
				(justify left bottom)
				(hide yes)
			)
		)
		(property "Manufacturer" "Würth Elektronik"
			(at 257.175 222.25 0)
			(effects
				(font
					(size 1.27 1.27)
					(thickness 0.15)
				)
				(justify left bottom)
				(hide yes)
			)
		)
		(property "Author" "Antmicro"
			(at 257.175 224.79 0)
			(effects
				(font
					(size 1.27 1.27)
					(thickness 0.15)
				)
				(justify left bottom)
				(hide yes)
			)
		)
		(property "License" "Apache-2.0"
			(at 257.175 227.33 0)
			(effects
				(font
					(size 1.27 1.27)
					(thickness 0.15)
				)
				(justify left bottom)
				(hide yes)
			)
		)
		(pin "1"
		)
		(pin "10"
		)
		(pin "11"
		)
		(pin "12"
		)
		(pin "13"
		)
		(pin "14"
		)
		(pin "2"
		)
		(pin "3"
		)
		(pin "4"
		)
		(pin "5"
		)
		(pin "6"
		)
		(pin "7"
		)
		(pin "8"
		)
		(pin "9"
		)
		(pin "SH"
		)
		(pin "SH"
		)
		(instances
			(project "lpddr4-test-board"
				(path ""
					(reference "J5")
					(unit 1)
				)
			)
		)
	)
	(symbol
		(lib_id "antmicroFerriteBeadsandChips:FB_120Z_2A_Murata-BLM18PG_0603")
		(at 212.725 245.11 270)
		(unit 1)
		(exclude_from_sim no)
		(in_bom yes)
		(on_board yes)
		(dnp no)
		(property "Reference" "FB7"
			(at 215.265 247.65 90)
			(effects
				(font
					(size 1.27 1.27)
					(thickness 0.15)
				)
				(justify left bottom)
			)
		)
		(property "Value" "FB_120Z_2A_0603"
			(at 207.645 260.35 0)
			(effects
				(font
					(size 1.27 1.27)
					(thickness 0.15)
				)
				(justify left bottom)
				(hide yes)
			)
		)
		(property "Footprint" "antmicro-footprints:FB_0603_1608Metric"
			(at 205.105 260.35 0)
			(effects
				(font
					(size 1.27 1.27)
					(thickness 0.15)
				)
				(justify left bottom)
				(hide yes)
			)
		)
		(property "Datasheet" "https://www.murata.com/en-us/products/productdata/8796738650142/ENFA0003.pdf"
			(at 202.565 260.35 0)
			(effects
				(font
					(size 1.27 1.27)
					(thickness 0.15)
				)
				(justify left bottom)
				(hide yes)
			)
		)
		(property "Description" ""
			(at 212.725 245.11 0)
			(effects
				(font
					(size 1.27 1.27)
				)
			)
		)
		(property "MPN" "BLM18PG121SN1D"
			(at 215.265 250.19 90)
			(effects
				(font
					(size 1.27 1.27)
					(thickness 0.15)
				)
				(justify left bottom)
			)
		)
		(property "Manufacturer" "Murata"
			(at 197.485 260.35 0)
			(effects
				(font
					(size 1.27 1.27)
					(thickness 0.15)
				)
				(justify left bottom)
				(hide yes)
			)
		)
		(property "Author" "Antmicro"
			(at 194.945 260.35 0)
			(effects
				(font
					(size 1.27 1.27)
					(thickness 0.15)
				)
				(justify left bottom)
				(hide yes)
			)
		)
		(property "License" "Apache-2.0"
			(at 192.405 260.35 0)
			(effects
				(font
					(size 1.27 1.27)
					(thickness 0.15)
				)
				(justify left bottom)
				(hide yes)
			)
		)
		(pin "1"
		)
		(pin "2"
		)
		(instances
			(project "lpddr4-test-board"
				(path ""
					(reference "FB7")
					(unit 1)
				)
			)
		)
	)
	(symbol
		(lib_id "antmicropower:GND")
		(at 212.725 252.73 0)
		(unit 1)
		(exclude_from_sim no)
		(in_bom yes)
		(on_board yes)
		(dnp no)
		(property "Reference" "#PWR0139"
			(at 221.615 255.27 0)
			(effects
				(font
					(size 1.27 1.27)
					(thickness 0.15)
				)
				(justify left bottom)
				(hide yes)
			)
		)
		(property "Value" "GND"
			(at 210.82 257.175 0)
			(effects
				(font
					(size 1.27 1.27)
					(thickness 0.15)
				)
				(justify left bottom)
			)
		)
		(property "Footprint" ""
			(at 221.615 260.35 0)
			(effects
				(font
					(size 1.27 1.27)
					(thickness 0.15)
				)
				(justify left bottom)
				(hide yes)
			)
		)
		(property "Datasheet" ""
			(at 221.615 265.43 0)
			(effects
				(font
					(size 1.27 1.27)
					(thickness 0.15)
				)
				(justify left bottom)
				(hide yes)
			)
		)
		(property "Description" ""
			(at 212.725 252.73 0)
			(effects
				(font
					(size 1.27 1.27)
				)
			)
		)
		(property "Author" "Antmicro"
			(at 221.615 260.35 0)
			(effects
				(font
					(size 1.27 1.27)
					(thickness 0.15)
				)
				(justify left bottom)
				(hide yes)
			)
		)
		(property "License" "Apache-2.0"
			(at 221.615 262.89 0)
			(effects
				(font
					(size 1.27 1.27)
					(thickness 0.15)
				)
				(justify left bottom)
				(hide yes)
			)
		)
		(pin "1"
		)
		(instances
			(project "lpddr4-test-board"
				(path ""
					(reference "#PWR0139")
					(unit 1)
				)
			)
		)
	)
	(symbol
		(lib_id "antmicroResistors0402:R_220R_0402")
		(at 250.825 207.01 270)
		(mirror x)
		(unit 1)
		(exclude_from_sim no)
		(in_bom yes)
		(on_board yes)
		(dnp no)
		(property "Reference" "R70"
			(at 252.095 204.47 90)
			(effects
				(font
					(size 1.27 1.27)
					(thickness 0.15)
				)
				(justify left top)
			)
		)
		(property "Value" "R_220R_0402"
			(at 238.125 186.69 0)
			(effects
				(font
					(size 1.27 1.27)
					(thickness 0.15)
				)
				(justify left bottom)
				(hide yes)
			)
		)
		(property "Footprint" "antmicro-footprints:R_0402_1005Metric"
			(at 235.585 186.69 0)
			(effects
				(font
					(size 1.27 1.27)
					(thickness 0.15)
				)
				(justify left bottom)
				(hide yes)
			)
		)
		(property "Datasheet" "https://www.bourns.com/docs/product-datasheets/cr.pdf"
			(at 233.045 186.69 0)
			(effects
				(font
					(size 1.27 1.27)
					(thickness 0.15)
				)
				(justify left bottom)
				(hide yes)
			)
		)
		(property "Description" ""
			(at 250.825 207.01 0)
			(effects
				(font
					(size 1.27 1.27)
				)
			)
		)
		(property "Manufacturer" "Bourns"
			(at 227.965 186.69 0)
			(effects
				(font
					(size 1.27 1.27)
					(thickness 0.15)
				)
				(justify left bottom)
				(hide yes)
			)
		)
		(property "MPN" "CR0402-FX-2200GLF"
			(at 230.505 186.69 0)
			(effects
				(font
					(size 1.27 1.27)
					(thickness 0.15)
				)
				(justify left bottom)
				(hide yes)
			)
		)
		(property "Val" "220R"
			(at 252.095 206.375 90)
			(effects
				(font
					(size 1.27 1.27)
					(thickness 0.15)
				)
				(justify left top)
			)
		)
		(property "License" "Apache-2.0"
			(at 225.425 186.69 0)
			(effects
				(font
					(size 1.27 1.27)
					(thickness 0.15)
				)
				(justify left bottom)
				(hide yes)
			)
		)
		(property "Author" "Antmicro"
			(at 222.885 186.69 0)
			(effects
				(font
					(size 1.27 1.27)
					(thickness 0.15)
				)
				(justify left bottom)
				(hide yes)
			)
		)
		(property "Tolerance" "1%"
			(at 240.665 186.69 0)
			(effects
				(font
					(size 1.27 1.27)
				)
				(justify left bottom)
				(hide yes)
			)
		)
		(pin "1"
		)
		(pin "2"
		)
		(instances
			(project "lpddr4-test-board"
				(path ""
					(reference "R70")
					(unit 1)
				)
			)
		)
	)
	(symbol
		(lib_id "antmicroResistors0402:R_220R_0402")
		(at 260.35 207.01 270)
		(mirror x)
		(unit 1)
		(exclude_from_sim no)
		(in_bom yes)
		(on_board yes)
		(dnp no)
		(property "Reference" "R71"
			(at 261.62 204.47 90)
			(effects
				(font
					(size 1.27 1.27)
					(thickness 0.15)
				)
				(justify left top)
			)
		)
		(property "Value" "R_220R_0402"
			(at 247.65 186.69 0)
			(effects
				(font
					(size 1.27 1.27)
					(thickness 0.15)
				)
				(justify left bottom)
				(hide yes)
			)
		)
		(property "Footprint" "antmicro-footprints:R_0402_1005Metric"
			(at 245.11 186.69 0)
			(effects
				(font
					(size 1.27 1.27)
					(thickness 0.15)
				)
				(justify left bottom)
				(hide yes)
			)
		)
		(property "Datasheet" "https://www.bourns.com/docs/product-datasheets/cr.pdf"
			(at 242.57 186.69 0)
			(effects
				(font
					(size 1.27 1.27)
					(thickness 0.15)
				)
				(justify left bottom)
				(hide yes)
			)
		)
		(property "Description" ""
			(at 260.35 207.01 0)
			(effects
				(font
					(size 1.27 1.27)
				)
			)
		)
		(property "Manufacturer" "Bourns"
			(at 237.49 186.69 0)
			(effects
				(font
					(size 1.27 1.27)
					(thickness 0.15)
				)
				(justify left bottom)
				(hide yes)
			)
		)
		(property "MPN" "CR0402-FX-2200GLF"
			(at 240.03 186.69 0)
			(effects
				(font
					(size 1.27 1.27)
					(thickness 0.15)
				)
				(justify left bottom)
				(hide yes)
			)
		)
		(property "Val" "220R"
			(at 261.62 206.375 90)
			(effects
				(font
					(size 1.27 1.27)
					(thickness 0.15)
				)
				(justify left top)
			)
		)
		(property "License" "Apache-2.0"
			(at 234.95 186.69 0)
			(effects
				(font
					(size 1.27 1.27)
					(thickness 0.15)
				)
				(justify left bottom)
				(hide yes)
			)
		)
		(property "Author" "Antmicro"
			(at 232.41 186.69 0)
			(effects
				(font
					(size 1.27 1.27)
					(thickness 0.15)
				)
				(justify left bottom)
				(hide yes)
			)
		)
		(property "Tolerance" "1%"
			(at 250.19 186.69 0)
			(effects
				(font
					(size 1.27 1.27)
				)
				(justify left bottom)
				(hide yes)
			)
		)
		(pin "1"
		)
		(pin "2"
		)
		(instances
			(project "lpddr4-test-board"
				(path ""
					(reference "R71")
					(unit 1)
				)
			)
		)
	)
	(symbol
		(lib_id "antmicroResistors0402:R_1k_0402")
		(at 361.315 175.895 0)
		(unit 1)
		(exclude_from_sim no)
		(in_bom yes)
		(on_board yes)
		(dnp no)
		(property "Reference" "R83"
			(at 366.395 175.895 0)
			(effects
				(font
					(size 1.27 1.27)
					(thickness 0.15)
				)
				(justify left bottom)
			)
		)
		(property "Value" "R_1k_0402"
			(at 381.635 188.595 0)
			(effects
				(font
					(size 1.27 1.27)
					(thickness 0.15)
				)
				(justify left bottom)
				(hide yes)
			)
		)
		(property "Footprint" "antmicro-footprints:R_0402_1005Metric"
			(at 381.635 191.135 0)
			(effects
				(font
					(size 1.27 1.27)
					(thickness 0.15)
				)
				(justify left bottom)
				(hide yes)
			)
		)
		(property "Datasheet" "https://www.bourns.com/docs/product-datasheets/cr.pdf"
			(at 381.635 193.675 0)
			(effects
				(font
					(size 1.27 1.27)
					(thickness 0.15)
				)
				(justify left bottom)
				(hide yes)
			)
		)
		(property "Description" ""
			(at 361.315 175.895 0)
			(effects
				(font
					(size 1.27 1.27)
				)
			)
		)
		(property "Manufacturer" "Bourns"
			(at 381.635 198.755 0)
			(effects
				(font
					(size 1.27 1.27)
					(thickness 0.15)
				)
				(justify left bottom)
				(hide yes)
			)
		)
		(property "MPN" "CR0402-FX-1001GLF"
			(at 381.635 196.215 0)
			(effects
				(font
					(size 1.27 1.27)
					(thickness 0.15)
				)
				(justify left bottom)
				(hide yes)
			)
		)
		(property "Val" "1k"
			(at 356.235 175.895 0)
			(effects
				(font
					(size 1.27 1.27)
					(thickness 0.15)
				)
				(justify left bottom)
			)
		)
		(property "License" "Apache-2.0"
			(at 381.635 201.295 0)
			(effects
				(font
					(size 1.27 1.27)
					(thickness 0.15)
				)
				(justify left bottom)
				(hide yes)
			)
		)
		(property "Author" "Antmicro"
			(at 381.635 203.835 0)
			(effects
				(font
					(size 1.27 1.27)
					(thickness 0.15)
				)
				(justify left bottom)
				(hide yes)
			)
		)
		(property "Tolerance" "1%"
			(at 381.635 186.055 0)
			(effects
				(font
					(size 1.27 1.27)
				)
				(justify left bottom)
				(hide yes)
			)
		)
		(pin "1"
		)
		(pin "2"
		)
		(instances
			(project "lpddr4-test-board"
				(path ""
					(reference "R83")
					(unit 1)
				)
			)
		)
	)
	(symbol
		(lib_id "antmicroResistors0402:R_2k2_0402")
		(at 360.045 85.09 0)
		(unit 1)
		(exclude_from_sim no)
		(in_bom yes)
		(on_board yes)
		(dnp no)
		(property "Reference" "R85"
			(at 365.125 85.09 0)
			(effects
				(font
					(size 1.27 1.27)
					(thickness 0.15)
				)
				(justify left bottom)
			)
		)
		(property "Value" "R_2k2_0402"
			(at 380.365 97.79 0)
			(effects
				(font
					(size 1.27 1.27)
					(thickness 0.15)
				)
				(justify left bottom)
				(hide yes)
			)
		)
		(property "Footprint" "antmicro-footprints:R_0402_1005Metric"
			(at 380.365 100.33 0)
			(effects
				(font
					(size 1.27 1.27)
					(thickness 0.15)
				)
				(justify left bottom)
				(hide yes)
			)
		)
		(property "Datasheet" "https://www.bourns.com/docs/product-datasheets/cr.pdf"
			(at 380.365 102.87 0)
			(effects
				(font
					(size 1.27 1.27)
					(thickness 0.15)
				)
				(justify left bottom)
				(hide yes)
			)
		)
		(property "Description" ""
			(at 360.045 85.09 0)
			(effects
				(font
					(size 1.27 1.27)
				)
			)
		)
		(property "Manufacturer" "Bourns"
			(at 380.365 107.95 0)
			(effects
				(font
					(size 1.27 1.27)
					(thickness 0.15)
				)
				(justify left bottom)
				(hide yes)
			)
		)
		(property "MPN" "CR0402-FX-2201GLF"
			(at 380.365 105.41 0)
			(effects
				(font
					(size 1.27 1.27)
					(thickness 0.15)
				)
				(justify left bottom)
				(hide yes)
			)
		)
		(property "Val" "2k2"
			(at 356.235 85.09 0)
			(effects
				(font
					(size 1.27 1.27)
					(thickness 0.15)
				)
				(justify left bottom)
			)
		)
		(property "License" "Apache-2.0"
			(at 380.365 110.49 0)
			(effects
				(font
					(size 1.27 1.27)
					(thickness 0.15)
				)
				(justify left bottom)
				(hide yes)
			)
		)
		(property "Author" "Antmicro"
			(at 380.365 113.03 0)
			(effects
				(font
					(size 1.27 1.27)
					(thickness 0.15)
				)
				(justify left bottom)
				(hide yes)
			)
		)
		(property "Tolerance" "1%"
			(at 380.365 95.25 0)
			(effects
				(font
					(size 1.27 1.27)
				)
				(justify left bottom)
				(hide yes)
			)
		)
		(pin "1"
		)
		(pin "2"
		)
		(instances
			(project "lpddr4-test-board"
				(path ""
					(reference "R85")
					(unit 1)
				)
			)
		)
	)
	(symbol
		(lib_id "antmicroResistors0402:R_2k2_0402")
		(at 360.045 87.63 0)
		(unit 1)
		(exclude_from_sim no)
		(in_bom yes)
		(on_board yes)
		(dnp no)
		(property "Reference" "R86"
			(at 365.125 87.63 0)
			(effects
				(font
					(size 1.27 1.27)
					(thickness 0.15)
				)
				(justify left bottom)
			)
		)
		(property "Value" "R_2k2_0402"
			(at 380.365 100.33 0)
			(effects
				(font
					(size 1.27 1.27)
					(thickness 0.15)
				)
				(justify left bottom)
				(hide yes)
			)
		)
		(property "Footprint" "antmicro-footprints:R_0402_1005Metric"
			(at 380.365 102.87 0)
			(effects
				(font
					(size 1.27 1.27)
					(thickness 0.15)
				)
				(justify left bottom)
				(hide yes)
			)
		)
		(property "Datasheet" "https://www.bourns.com/docs/product-datasheets/cr.pdf"
			(at 380.365 105.41 0)
			(effects
				(font
					(size 1.27 1.27)
					(thickness 0.15)
				)
				(justify left bottom)
				(hide yes)
			)
		)
		(property "Description" ""
			(at 360.045 87.63 0)
			(effects
				(font
					(size 1.27 1.27)
				)
			)
		)
		(property "Manufacturer" "Bourns"
			(at 380.365 110.49 0)
			(effects
				(font
					(size 1.27 1.27)
					(thickness 0.15)
				)
				(justify left bottom)
				(hide yes)
			)
		)
		(property "MPN" "CR0402-FX-2201GLF"
			(at 380.365 107.95 0)
			(effects
				(font
					(size 1.27 1.27)
					(thickness 0.15)
				)
				(justify left bottom)
				(hide yes)
			)
		)
		(property "Val" "2k2"
			(at 356.235 87.63 0)
			(effects
				(font
					(size 1.27 1.27)
					(thickness 0.15)
				)
				(justify left bottom)
			)
		)
		(property "License" "Apache-2.0"
			(at 380.365 113.03 0)
			(effects
				(font
					(size 1.27 1.27)
					(thickness 0.15)
				)
				(justify left bottom)
				(hide yes)
			)
		)
		(property "Author" "Antmicro"
			(at 380.365 115.57 0)
			(effects
				(font
					(size 1.27 1.27)
					(thickness 0.15)
				)
				(justify left bottom)
				(hide yes)
			)
		)
		(property "Tolerance" "1%"
			(at 380.365 97.79 0)
			(effects
				(font
					(size 1.27 1.27)
				)
				(justify left bottom)
				(hide yes)
			)
		)
		(pin "1"
		)
		(pin "2"
		)
		(instances
			(project "lpddr4-test-board"
				(path ""
					(reference "R86")
					(unit 1)
				)
			)
		)
	)
	(symbol
		(lib_id "antmicroResistors0402:R_2k2_0402")
		(at 360.045 90.17 0)
		(unit 1)
		(exclude_from_sim no)
		(in_bom no)
		(on_board yes)
		(dnp yes)
		(property "Reference" "R87"
			(at 365.125 90.17 0)
			(effects
				(font
					(size 1.27 1.27)
					(thickness 0.15)
				)
				(justify left bottom)
			)
		)
		(property "Value" "R_2k2_0402"
			(at 380.365 102.87 0)
			(effects
				(font
					(size 1.27 1.27)
					(thickness 0.15)
				)
				(justify left bottom)
				(hide yes)
			)
		)
		(property "Footprint" "antmicro-footprints:R_0402_1005Metric"
			(at 380.365 105.41 0)
			(effects
				(font
					(size 1.27 1.27)
					(thickness 0.15)
				)
				(justify left bottom)
				(hide yes)
			)
		)
		(property "Datasheet" "https://www.bourns.com/docs/product-datasheets/cr.pdf"
			(at 380.365 107.95 0)
			(effects
				(font
					(size 1.27 1.27)
					(thickness 0.15)
				)
				(justify left bottom)
				(hide yes)
			)
		)
		(property "Description" ""
			(at 360.045 90.17 0)
			(effects
				(font
					(size 1.27 1.27)
				)
			)
		)
		(property "Manufacturer" "Bourns"
			(at 380.365 113.03 0)
			(effects
				(font
					(size 1.27 1.27)
					(thickness 0.15)
				)
				(justify left bottom)
				(hide yes)
			)
		)
		(property "MPN" "CR0402-FX-2201GLF"
			(at 380.365 110.49 0)
			(effects
				(font
					(size 1.27 1.27)
					(thickness 0.15)
				)
				(justify left bottom)
				(hide yes)
			)
		)
		(property "Val" "2k2"
			(at 356.235 90.17 0)
			(effects
				(font
					(size 1.27 1.27)
					(thickness 0.15)
				)
				(justify left bottom)
			)
		)
		(property "License" "Apache-2.0"
			(at 380.365 115.57 0)
			(effects
				(font
					(size 1.27 1.27)
					(thickness 0.15)
				)
				(justify left bottom)
				(hide yes)
			)
		)
		(property "Author" "Antmicro"
			(at 380.365 118.11 0)
			(effects
				(font
					(size 1.27 1.27)
					(thickness 0.15)
				)
				(justify left bottom)
				(hide yes)
			)
		)
		(property "Tolerance" "1%"
			(at 380.365 100.33 0)
			(effects
				(font
					(size 1.27 1.27)
				)
				(justify left bottom)
				(hide yes)
			)
		)
		(pin "1"
		)
		(pin "2"
		)
		(instances
			(project "lpddr4-test-board"
				(path ""
					(reference "R87")
					(unit 1)
				)
			)
		)
	)
	(symbol
		(lib_id "antmicroResistors0402:R_2k2_0402")
		(at 360.045 92.71 0)
		(unit 1)
		(exclude_from_sim no)
		(in_bom no)
		(on_board yes)
		(dnp yes)
		(property "Reference" "R88"
			(at 365.125 92.71 0)
			(effects
				(font
					(size 1.27 1.27)
					(thickness 0.15)
				)
				(justify left bottom)
			)
		)
		(property "Value" "R_2k2_0402"
			(at 380.365 105.41 0)
			(effects
				(font
					(size 1.27 1.27)
					(thickness 0.15)
				)
				(justify left bottom)
				(hide yes)
			)
		)
		(property "Footprint" "antmicro-footprints:R_0402_1005Metric"
			(at 380.365 107.95 0)
			(effects
				(font
					(size 1.27 1.27)
					(thickness 0.15)
				)
				(justify left bottom)
				(hide yes)
			)
		)
		(property "Datasheet" "https://www.bourns.com/docs/product-datasheets/cr.pdf"
			(at 380.365 110.49 0)
			(effects
				(font
					(size 1.27 1.27)
					(thickness 0.15)
				)
				(justify left bottom)
				(hide yes)
			)
		)
		(property "Description" ""
			(at 360.045 92.71 0)
			(effects
				(font
					(size 1.27 1.27)
				)
			)
		)
		(property "Manufacturer" "Bourns"
			(at 380.365 115.57 0)
			(effects
				(font
					(size 1.27 1.27)
					(thickness 0.15)
				)
				(justify left bottom)
				(hide yes)
			)
		)
		(property "MPN" "CR0402-FX-2201GLF"
			(at 380.365 113.03 0)
			(effects
				(font
					(size 1.27 1.27)
					(thickness 0.15)
				)
				(justify left bottom)
				(hide yes)
			)
		)
		(property "Val" "2k2"
			(at 356.235 92.71 0)
			(effects
				(font
					(size 1.27 1.27)
					(thickness 0.15)
				)
				(justify left bottom)
			)
		)
		(property "License" "Apache-2.0"
			(at 380.365 118.11 0)
			(effects
				(font
					(size 1.27 1.27)
					(thickness 0.15)
				)
				(justify left bottom)
				(hide yes)
			)
		)
		(property "Author" "Antmicro"
			(at 380.365 120.65 0)
			(effects
				(font
					(size 1.27 1.27)
					(thickness 0.15)
				)
				(justify left bottom)
				(hide yes)
			)
		)
		(property "Tolerance" "1%"
			(at 380.365 102.87 0)
			(effects
				(font
					(size 1.27 1.27)
				)
				(justify left bottom)
				(hide yes)
			)
		)
		(pin "1"
		)
		(pin "2"
		)
		(instances
			(project "lpddr4-test-board"
				(path ""
					(reference "R88")
					(unit 1)
				)
			)
		)
	)
	(symbol
		(lib_id "antmicroResistors0402:R_2k2_0402")
		(at 360.045 95.25 0)
		(unit 1)
		(exclude_from_sim no)
		(in_bom yes)
		(on_board yes)
		(dnp no)
		(property "Reference" "R89"
			(at 365.125 95.25 0)
			(effects
				(font
					(size 1.27 1.27)
					(thickness 0.15)
				)
				(justify left bottom)
			)
		)
		(property "Value" "R_2k2_0402"
			(at 380.365 107.95 0)
			(effects
				(font
					(size 1.27 1.27)
					(thickness 0.15)
				)
				(justify left bottom)
				(hide yes)
			)
		)
		(property "Footprint" "antmicro-footprints:R_0402_1005Metric"
			(at 380.365 110.49 0)
			(effects
				(font
					(size 1.27 1.27)
					(thickness 0.15)
				)
				(justify left bottom)
				(hide yes)
			)
		)
		(property "Datasheet" "https://www.bourns.com/docs/product-datasheets/cr.pdf"
			(at 380.365 113.03 0)
			(effects
				(font
					(size 1.27 1.27)
					(thickness 0.15)
				)
				(justify left bottom)
				(hide yes)
			)
		)
		(property "Description" ""
			(at 360.045 95.25 0)
			(effects
				(font
					(size 1.27 1.27)
				)
			)
		)
		(property "Manufacturer" "Bourns"
			(at 380.365 118.11 0)
			(effects
				(font
					(size 1.27 1.27)
					(thickness 0.15)
				)
				(justify left bottom)
				(hide yes)
			)
		)
		(property "MPN" "CR0402-FX-2201GLF"
			(at 380.365 115.57 0)
			(effects
				(font
					(size 1.27 1.27)
					(thickness 0.15)
				)
				(justify left bottom)
				(hide yes)
			)
		)
		(property "Val" "2k2"
			(at 356.235 95.25 0)
			(effects
				(font
					(size 1.27 1.27)
					(thickness 0.15)
				)
				(justify left bottom)
			)
		)
		(property "License" "Apache-2.0"
			(at 380.365 120.65 0)
			(effects
				(font
					(size 1.27 1.27)
					(thickness 0.15)
				)
				(justify left bottom)
				(hide yes)
			)
		)
		(property "Author" "Antmicro"
			(at 380.365 123.19 0)
			(effects
				(font
					(size 1.27 1.27)
					(thickness 0.15)
				)
				(justify left bottom)
				(hide yes)
			)
		)
		(property "Tolerance" "1%"
			(at 380.365 105.41 0)
			(effects
				(font
					(size 1.27 1.27)
				)
				(justify left bottom)
				(hide yes)
			)
		)
		(pin "1"
		)
		(pin "2"
		)
		(instances
			(project "lpddr4-test-board"
				(path ""
					(reference "R89")
					(unit 1)
				)
			)
		)
	)
	(symbol
		(lib_id "antmicroResistors0402:R_2k2_0402")
		(at 360.045 102.87 0)
		(unit 1)
		(exclude_from_sim no)
		(in_bom no)
		(on_board yes)
		(dnp yes)
		(property "Reference" "R92"
			(at 365.125 102.87 0)
			(effects
				(font
					(size 1.27 1.27)
					(thickness 0.15)
				)
				(justify left bottom)
			)
		)
		(property "Value" "R_2k2_0402"
			(at 380.365 115.57 0)
			(effects
				(font
					(size 1.27 1.27)
					(thickness 0.15)
				)
				(justify left bottom)
				(hide yes)
			)
		)
		(property "Footprint" "antmicro-footprints:R_0402_1005Metric"
			(at 380.365 118.11 0)
			(effects
				(font
					(size 1.27 1.27)
					(thickness 0.15)
				)
				(justify left bottom)
				(hide yes)
			)
		)
		(property "Datasheet" "https://www.bourns.com/docs/product-datasheets/cr.pdf"
			(at 380.365 120.65 0)
			(effects
				(font
					(size 1.27 1.27)
					(thickness 0.15)
				)
				(justify left bottom)
				(hide yes)
			)
		)
		(property "Description" ""
			(at 360.045 102.87 0)
			(effects
				(font
					(size 1.27 1.27)
				)
			)
		)
		(property "Manufacturer" "Bourns"
			(at 380.365 125.73 0)
			(effects
				(font
					(size 1.27 1.27)
					(thickness 0.15)
				)
				(justify left bottom)
				(hide yes)
			)
		)
		(property "MPN" "CR0402-FX-2201GLF"
			(at 380.365 123.19 0)
			(effects
				(font
					(size 1.27 1.27)
					(thickness 0.15)
				)
				(justify left bottom)
				(hide yes)
			)
		)
		(property "Val" "2k2"
			(at 356.235 102.87 0)
			(effects
				(font
					(size 1.27 1.27)
					(thickness 0.15)
				)
				(justify left bottom)
			)
		)
		(property "License" "Apache-2.0"
			(at 380.365 128.27 0)
			(effects
				(font
					(size 1.27 1.27)
					(thickness 0.15)
				)
				(justify left bottom)
				(hide yes)
			)
		)
		(property "Author" "Antmicro"
			(at 380.365 130.81 0)
			(effects
				(font
					(size 1.27 1.27)
					(thickness 0.15)
				)
				(justify left bottom)
				(hide yes)
			)
		)
		(property "Tolerance" "1%"
			(at 380.365 113.03 0)
			(effects
				(font
					(size 1.27 1.27)
				)
				(justify left bottom)
				(hide yes)
			)
		)
		(pin "1"
		)
		(pin "2"
		)
		(instances
			(project "lpddr4-test-board"
				(path ""
					(reference "R92")
					(unit 1)
				)
			)
		)
	)
	(symbol
		(lib_id "antmicroResistors0402:R_2k2_0402")
		(at 360.045 105.41 0)
		(unit 1)
		(exclude_from_sim no)
		(in_bom no)
		(on_board yes)
		(dnp yes)
		(property "Reference" "R93"
			(at 365.125 105.41 0)
			(effects
				(font
					(size 1.27 1.27)
					(thickness 0.15)
				)
				(justify left bottom)
			)
		)
		(property "Value" "R_2k2_0402"
			(at 380.365 118.11 0)
			(effects
				(font
					(size 1.27 1.27)
					(thickness 0.15)
				)
				(justify left bottom)
				(hide yes)
			)
		)
		(property "Footprint" "antmicro-footprints:R_0402_1005Metric"
			(at 380.365 120.65 0)
			(effects
				(font
					(size 1.27 1.27)
					(thickness 0.15)
				)
				(justify left bottom)
				(hide yes)
			)
		)
		(property "Datasheet" "https://www.bourns.com/docs/product-datasheets/cr.pdf"
			(at 380.365 123.19 0)
			(effects
				(font
					(size 1.27 1.27)
					(thickness 0.15)
				)
				(justify left bottom)
				(hide yes)
			)
		)
		(property "Description" ""
			(at 360.045 105.41 0)
			(effects
				(font
					(size 1.27 1.27)
				)
			)
		)
		(property "Manufacturer" "Bourns"
			(at 380.365 128.27 0)
			(effects
				(font
					(size 1.27 1.27)
					(thickness 0.15)
				)
				(justify left bottom)
				(hide yes)
			)
		)
		(property "MPN" "CR0402-FX-2201GLF"
			(at 380.365 125.73 0)
			(effects
				(font
					(size 1.27 1.27)
					(thickness 0.15)
				)
				(justify left bottom)
				(hide yes)
			)
		)
		(property "Val" "2k2"
			(at 356.235 105.41 0)
			(effects
				(font
					(size 1.27 1.27)
					(thickness 0.15)
				)
				(justify left bottom)
			)
		)
		(property "License" "Apache-2.0"
			(at 380.365 130.81 0)
			(effects
				(font
					(size 1.27 1.27)
					(thickness 0.15)
				)
				(justify left bottom)
				(hide yes)
			)
		)
		(property "Author" "Antmicro"
			(at 380.365 133.35 0)
			(effects
				(font
					(size 1.27 1.27)
					(thickness 0.15)
				)
				(justify left bottom)
				(hide yes)
			)
		)
		(property "Tolerance" "1%"
			(at 380.365 115.57 0)
			(effects
				(font
					(size 1.27 1.27)
				)
				(justify left bottom)
				(hide yes)
			)
		)
		(pin "1"
		)
		(pin "2"
		)
		(instances
			(project "lpddr4-test-board"
				(path ""
					(reference "R93")
					(unit 1)
				)
			)
		)
	)
	(symbol
		(lib_id "antmicroResistors0402:R_2k2_0402")
		(at 360.045 100.33 0)
		(unit 1)
		(exclude_from_sim no)
		(in_bom no)
		(on_board yes)
		(dnp yes)
		(property "Reference" "R91"
			(at 365.125 100.33 0)
			(effects
				(font
					(size 1.27 1.27)
					(thickness 0.15)
				)
				(justify left bottom)
			)
		)
		(property "Value" "R_2k2_0402"
			(at 380.365 113.03 0)
			(effects
				(font
					(size 1.27 1.27)
					(thickness 0.15)
				)
				(justify left bottom)
				(hide yes)
			)
		)
		(property "Footprint" "antmicro-footprints:R_0402_1005Metric"
			(at 380.365 115.57 0)
			(effects
				(font
					(size 1.27 1.27)
					(thickness 0.15)
				)
				(justify left bottom)
				(hide yes)
			)
		)
		(property "Datasheet" "https://www.bourns.com/docs/product-datasheets/cr.pdf"
			(at 380.365 118.11 0)
			(effects
				(font
					(size 1.27 1.27)
					(thickness 0.15)
				)
				(justify left bottom)
				(hide yes)
			)
		)
		(property "Description" ""
			(at 360.045 100.33 0)
			(effects
				(font
					(size 1.27 1.27)
				)
			)
		)
		(property "Manufacturer" "Bourns"
			(at 380.365 123.19 0)
			(effects
				(font
					(size 1.27 1.27)
					(thickness 0.15)
				)
				(justify left bottom)
				(hide yes)
			)
		)
		(property "MPN" "CR0402-FX-2201GLF"
			(at 380.365 120.65 0)
			(effects
				(font
					(size 1.27 1.27)
					(thickness 0.15)
				)
				(justify left bottom)
				(hide yes)
			)
		)
		(property "Val" "2k2"
			(at 356.235 100.33 0)
			(effects
				(font
					(size 1.27 1.27)
					(thickness 0.15)
				)
				(justify left bottom)
			)
		)
		(property "License" "Apache-2.0"
			(at 380.365 125.73 0)
			(effects
				(font
					(size 1.27 1.27)
					(thickness 0.15)
				)
				(justify left bottom)
				(hide yes)
			)
		)
		(property "Author" "Antmicro"
			(at 380.365 128.27 0)
			(effects
				(font
					(size 1.27 1.27)
					(thickness 0.15)
				)
				(justify left bottom)
				(hide yes)
			)
		)
		(property "Tolerance" "1%"
			(at 380.365 110.49 0)
			(effects
				(font
					(size 1.27 1.27)
				)
				(justify left bottom)
				(hide yes)
			)
		)
		(pin "1"
		)
		(pin "2"
		)
		(instances
			(project "lpddr4-test-board"
				(path ""
					(reference "R91")
					(unit 1)
				)
			)
		)
	)
	(symbol
		(lib_id "antmicropower:GND")
		(at 375.285 113.03 0)
		(unit 1)
		(exclude_from_sim no)
		(in_bom yes)
		(on_board yes)
		(dnp no)
		(property "Reference" "#PWR0143"
			(at 384.175 115.57 0)
			(effects
				(font
					(size 1.27 1.27)
					(thickness 0.15)
				)
				(justify left bottom)
				(hide yes)
			)
		)
		(property "Value" "GND"
			(at 373.38 117.475 0)
			(effects
				(font
					(size 1.27 1.27)
					(thickness 0.15)
				)
				(justify left bottom)
			)
		)
		(property "Footprint" ""
			(at 384.175 120.65 0)
			(effects
				(font
					(size 1.27 1.27)
					(thickness 0.15)
				)
				(justify left bottom)
				(hide yes)
			)
		)
		(property "Datasheet" ""
			(at 384.175 125.73 0)
			(effects
				(font
					(size 1.27 1.27)
					(thickness 0.15)
				)
				(justify left bottom)
				(hide yes)
			)
		)
		(property "Description" ""
			(at 375.285 113.03 0)
			(effects
				(font
					(size 1.27 1.27)
				)
			)
		)
		(property "Author" "Antmicro"
			(at 384.175 120.65 0)
			(effects
				(font
					(size 1.27 1.27)
					(thickness 0.15)
				)
				(justify left bottom)
				(hide yes)
			)
		)
		(property "License" "Apache-2.0"
			(at 384.175 123.19 0)
			(effects
				(font
					(size 1.27 1.27)
					(thickness 0.15)
				)
				(justify left bottom)
				(hide yes)
			)
		)
		(pin "1"
		)
		(instances
			(project "lpddr4-test-board"
				(path ""
					(reference "#PWR0143")
					(unit 1)
				)
			)
		)
	)
	(symbol
		(lib_id "antmicropower:GND")
		(at 77.47 161.29 0)
		(unit 1)
		(exclude_from_sim no)
		(in_bom yes)
		(on_board yes)
		(dnp no)
		(property "Reference" "#PWR0275"
			(at 86.36 163.83 0)
			(effects
				(font
					(size 1.27 1.27)
					(thickness 0.15)
				)
				(justify left bottom)
				(hide yes)
			)
		)
		(property "Value" "GND"
			(at 75.565 165.735 0)
			(effects
				(font
					(size 1.27 1.27)
					(thickness 0.15)
				)
				(justify left bottom)
			)
		)
		(property "Footprint" ""
			(at 86.36 168.91 0)
			(effects
				(font
					(size 1.27 1.27)
					(thickness 0.15)
				)
				(justify left bottom)
				(hide yes)
			)
		)
		(property "Datasheet" ""
			(at 86.36 173.99 0)
			(effects
				(font
					(size 1.27 1.27)
					(thickness 0.15)
				)
				(justify left bottom)
				(hide yes)
			)
		)
		(property "Description" ""
			(at 77.47 161.29 0)
			(effects
				(font
					(size 1.27 1.27)
				)
			)
		)
		(property "Author" "Antmicro"
			(at 86.36 168.91 0)
			(effects
				(font
					(size 1.27 1.27)
					(thickness 0.15)
				)
				(justify left bottom)
				(hide yes)
			)
		)
		(property "License" "Apache-2.0"
			(at 86.36 171.45 0)
			(effects
				(font
					(size 1.27 1.27)
					(thickness 0.15)
				)
				(justify left bottom)
				(hide yes)
			)
		)
		(pin "1"
		)
		(instances
			(project "lpddr4-test-board"
				(path ""
					(reference "#PWR0275")
					(unit 1)
				)
			)
		)
	)
	(symbol
		(lib_id "antmicropower:GND")
		(at 70.485 127 0)
		(unit 1)
		(exclude_from_sim no)
		(in_bom yes)
		(on_board yes)
		(dnp no)
		(property "Reference" "#PWR0288"
			(at 79.375 129.54 0)
			(effects
				(font
					(size 1.27 1.27)
					(thickness 0.15)
				)
				(justify left bottom)
				(hide yes)
			)
		)
		(property "Value" "GND"
			(at 68.58 131.445 0)
			(effects
				(font
					(size 1.27 1.27)
					(thickness 0.15)
				)
				(justify left bottom)
			)
		)
		(property "Footprint" ""
			(at 79.375 134.62 0)
			(effects
				(font
					(size 1.27 1.27)
					(thickness 0.15)
				)
				(justify left bottom)
				(hide yes)
			)
		)
		(property "Datasheet" ""
			(at 79.375 139.7 0)
			(effects
				(font
					(size 1.27 1.27)
					(thickness 0.15)
				)
				(justify left bottom)
				(hide yes)
			)
		)
		(property "Description" ""
			(at 70.485 127 0)
			(effects
				(font
					(size 1.27 1.27)
				)
			)
		)
		(property "Author" "Antmicro"
			(at 79.375 134.62 0)
			(effects
				(font
					(size 1.27 1.27)
					(thickness 0.15)
				)
				(justify left bottom)
				(hide yes)
			)
		)
		(property "License" "Apache-2.0"
			(at 79.375 137.16 0)
			(effects
				(font
					(size 1.27 1.27)
					(thickness 0.15)
				)
				(justify left bottom)
				(hide yes)
			)
		)
		(pin "1"
		)
		(instances
			(project "lpddr4-test-board"
				(path ""
					(reference "#PWR0288")
					(unit 1)
				)
			)
		)
	)
	(symbol
		(lib_id "antmicropower:GND")
		(at 56.515 161.29 0)
		(unit 1)
		(exclude_from_sim no)
		(in_bom yes)
		(on_board yes)
		(dnp no)
		(property "Reference" "#PWR0278"
			(at 65.405 163.83 0)
			(effects
				(font
					(size 1.27 1.27)
					(thickness 0.15)
				)
				(justify left bottom)
				(hide yes)
			)
		)
		(property "Value" "GND"
			(at 54.61 165.735 0)
			(effects
				(font
					(size 1.27 1.27)
					(thickness 0.15)
				)
				(justify left bottom)
			)
		)
		(property "Footprint" ""
			(at 65.405 168.91 0)
			(effects
				(font
					(size 1.27 1.27)
					(thickness 0.15)
				)
				(justify left bottom)
				(hide yes)
			)
		)
		(property "Datasheet" ""
			(at 65.405 173.99 0)
			(effects
				(font
					(size 1.27 1.27)
					(thickness 0.15)
				)
				(justify left bottom)
				(hide yes)
			)
		)
		(property "Description" ""
			(at 56.515 161.29 0)
			(effects
				(font
					(size 1.27 1.27)
				)
			)
		)
		(property "Author" "Antmicro"
			(at 65.405 168.91 0)
			(effects
				(font
					(size 1.27 1.27)
					(thickness 0.15)
				)
				(justify left bottom)
				(hide yes)
			)
		)
		(property "License" "Apache-2.0"
			(at 65.405 171.45 0)
			(effects
				(font
					(size 1.27 1.27)
					(thickness 0.15)
				)
				(justify left bottom)
				(hide yes)
			)
		)
		(pin "1"
		)
		(instances
			(project "lpddr4-test-board"
				(path ""
					(reference "#PWR0278")
					(unit 1)
				)
			)
		)
	)
	(symbol
		(lib_id "antmicropower:GND")
		(at 64.135 87.63 0)
		(unit 1)
		(exclude_from_sim no)
		(in_bom yes)
		(on_board yes)
		(dnp no)
		(property "Reference" "#PWR0272"
			(at 73.025 90.17 0)
			(effects
				(font
					(size 1.27 1.27)
					(thickness 0.15)
				)
				(justify left bottom)
				(hide yes)
			)
		)
		(property "Value" "GND"
			(at 62.23 92.075 0)
			(effects
				(font
					(size 1.27 1.27)
					(thickness 0.15)
				)
				(justify left bottom)
			)
		)
		(property "Footprint" ""
			(at 73.025 95.25 0)
			(effects
				(font
					(size 1.27 1.27)
					(thickness 0.15)
				)
				(justify left bottom)
				(hide yes)
			)
		)
		(property "Datasheet" ""
			(at 73.025 100.33 0)
			(effects
				(font
					(size 1.27 1.27)
					(thickness 0.15)
				)
				(justify left bottom)
				(hide yes)
			)
		)
		(property "Description" ""
			(at 64.135 87.63 0)
			(effects
				(font
					(size 1.27 1.27)
				)
			)
		)
		(property "Author" "Antmicro"
			(at 73.025 95.25 0)
			(effects
				(font
					(size 1.27 1.27)
					(thickness 0.15)
				)
				(justify left bottom)
				(hide yes)
			)
		)
		(property "License" "Apache-2.0"
			(at 73.025 97.79 0)
			(effects
				(font
					(size 1.27 1.27)
					(thickness 0.15)
				)
				(justify left bottom)
				(hide yes)
			)
		)
		(pin "1"
		)
		(instances
			(project "lpddr4-test-board"
				(path ""
					(reference "#PWR0272")
					(unit 1)
				)
			)
		)
	)
	(symbol
		(lib_id "antmicropower:GND")
		(at 78.105 87.63 0)
		(unit 1)
		(exclude_from_sim no)
		(in_bom yes)
		(on_board yes)
		(dnp no)
		(property "Reference" "#PWR0269"
			(at 86.995 90.17 0)
			(effects
				(font
					(size 1.27 1.27)
					(thickness 0.15)
				)
				(justify left bottom)
				(hide yes)
			)
		)
		(property "Value" "GND"
			(at 76.2 92.075 0)
			(effects
				(font
					(size 1.27 1.27)
					(thickness 0.15)
				)
				(justify left bottom)
			)
		)
		(property "Footprint" ""
			(at 86.995 95.25 0)
			(effects
				(font
					(size 1.27 1.27)
					(thickness 0.15)
				)
				(justify left bottom)
				(hide yes)
			)
		)
		(property "Datasheet" ""
			(at 86.995 100.33 0)
			(effects
				(font
					(size 1.27 1.27)
					(thickness 0.15)
				)
				(justify left bottom)
				(hide yes)
			)
		)
		(property "Description" ""
			(at 78.105 87.63 0)
			(effects
				(font
					(size 1.27 1.27)
				)
			)
		)
		(property "Author" "Antmicro"
			(at 86.995 95.25 0)
			(effects
				(font
					(size 1.27 1.27)
					(thickness 0.15)
				)
				(justify left bottom)
				(hide yes)
			)
		)
		(property "License" "Apache-2.0"
			(at 86.995 97.79 0)
			(effects
				(font
					(size 1.27 1.27)
					(thickness 0.15)
				)
				(justify left bottom)
				(hide yes)
			)
		)
		(pin "1"
		)
		(instances
			(project "lpddr4-test-board"
				(path ""
					(reference "#PWR0269")
					(unit 1)
				)
			)
		)
	)
	(symbol
		(lib_id "antmicropower:GND")
		(at 86.36 251.46 0)
		(unit 1)
		(exclude_from_sim no)
		(in_bom yes)
		(on_board yes)
		(dnp no)
		(property "Reference" "#PWR0285"
			(at 95.25 254 0)
			(effects
				(font
					(size 1.27 1.27)
					(thickness 0.15)
				)
				(justify left bottom)
				(hide yes)
			)
		)
		(property "Value" "GND"
			(at 84.455 255.905 0)
			(effects
				(font
					(size 1.27 1.27)
					(thickness 0.15)
				)
				(justify left bottom)
			)
		)
		(property "Footprint" ""
			(at 95.25 259.08 0)
			(effects
				(font
					(size 1.27 1.27)
					(thickness 0.15)
				)
				(justify left bottom)
				(hide yes)
			)
		)
		(property "Datasheet" ""
			(at 95.25 264.16 0)
			(effects
				(font
					(size 1.27 1.27)
					(thickness 0.15)
				)
				(justify left bottom)
				(hide yes)
			)
		)
		(property "Description" ""
			(at 86.36 251.46 0)
			(effects
				(font
					(size 1.27 1.27)
				)
			)
		)
		(property "Author" "Antmicro"
			(at 95.25 259.08 0)
			(effects
				(font
					(size 1.27 1.27)
					(thickness 0.15)
				)
				(justify left bottom)
				(hide yes)
			)
		)
		(property "License" "Apache-2.0"
			(at 95.25 261.62 0)
			(effects
				(font
					(size 1.27 1.27)
					(thickness 0.15)
				)
				(justify left bottom)
				(hide yes)
			)
		)
		(pin "1"
		)
		(instances
			(project "lpddr4-test-board"
				(path ""
					(reference "#PWR0285")
					(unit 1)
				)
			)
		)
	)
	(symbol
		(lib_id "antmicropower:GND")
		(at 207.645 252.73 0)
		(unit 1)
		(exclude_from_sim no)
		(in_bom yes)
		(on_board yes)
		(dnp no)
		(property "Reference" "#PWR0273"
			(at 216.535 255.27 0)
			(effects
				(font
					(size 1.27 1.27)
					(thickness 0.15)
				)
				(justify left bottom)
				(hide yes)
			)
		)
		(property "Value" "GND"
			(at 205.74 257.175 0)
			(effects
				(font
					(size 1.27 1.27)
					(thickness 0.15)
				)
				(justify left bottom)
			)
		)
		(property "Footprint" ""
			(at 216.535 260.35 0)
			(effects
				(font
					(size 1.27 1.27)
					(thickness 0.15)
				)
				(justify left bottom)
				(hide yes)
			)
		)
		(property "Datasheet" ""
			(at 216.535 265.43 0)
			(effects
				(font
					(size 1.27 1.27)
					(thickness 0.15)
				)
				(justify left bottom)
				(hide yes)
			)
		)
		(property "Description" ""
			(at 207.645 252.73 0)
			(effects
				(font
					(size 1.27 1.27)
				)
			)
		)
		(property "Author" "Antmicro"
			(at 216.535 260.35 0)
			(effects
				(font
					(size 1.27 1.27)
					(thickness 0.15)
				)
				(justify left bottom)
				(hide yes)
			)
		)
		(property "License" "Apache-2.0"
			(at 216.535 262.89 0)
			(effects
				(font
					(size 1.27 1.27)
					(thickness 0.15)
				)
				(justify left bottom)
				(hide yes)
			)
		)
		(pin "1"
		)
		(instances
			(project "lpddr4-test-board"
				(path ""
					(reference "#PWR0273")
					(unit 1)
				)
			)
		)
	)
	(symbol
		(lib_id "antmicropower:GND")
		(at 72.39 251.46 0)
		(unit 1)
		(exclude_from_sim no)
		(in_bom yes)
		(on_board yes)
		(dnp no)
		(property "Reference" "#PWR0280"
			(at 81.28 254 0)
			(effects
				(font
					(size 1.27 1.27)
					(thickness 0.15)
				)
				(justify left bottom)
				(hide yes)
			)
		)
		(property "Value" "GND"
			(at 70.485 255.905 0)
			(effects
				(font
					(size 1.27 1.27)
					(thickness 0.15)
				)
				(justify left bottom)
			)
		)
		(property "Footprint" ""
			(at 81.28 259.08 0)
			(effects
				(font
					(size 1.27 1.27)
					(thickness 0.15)
				)
				(justify left bottom)
				(hide yes)
			)
		)
		(property "Datasheet" ""
			(at 81.28 264.16 0)
			(effects
				(font
					(size 1.27 1.27)
					(thickness 0.15)
				)
				(justify left bottom)
				(hide yes)
			)
		)
		(property "Description" ""
			(at 72.39 251.46 0)
			(effects
				(font
					(size 1.27 1.27)
				)
			)
		)
		(property "Author" "Antmicro"
			(at 81.28 259.08 0)
			(effects
				(font
					(size 1.27 1.27)
					(thickness 0.15)
				)
				(justify left bottom)
				(hide yes)
			)
		)
		(property "License" "Apache-2.0"
			(at 81.28 261.62 0)
			(effects
				(font
					(size 1.27 1.27)
					(thickness 0.15)
				)
				(justify left bottom)
				(hide yes)
			)
		)
		(pin "1"
		)
		(instances
			(project "lpddr4-test-board"
				(path ""
					(reference "#PWR0280")
					(unit 1)
				)
			)
		)
	)
	(symbol
		(lib_id "antmicropower:GND")
		(at 92.075 87.63 0)
		(unit 1)
		(exclude_from_sim no)
		(in_bom yes)
		(on_board yes)
		(dnp no)
		(property "Reference" "#PWR0287"
			(at 100.965 90.17 0)
			(effects
				(font
					(size 1.27 1.27)
					(thickness 0.15)
				)
				(justify left bottom)
				(hide yes)
			)
		)
		(property "Value" "GND"
			(at 90.17 92.075 0)
			(effects
				(font
					(size 1.27 1.27)
					(thickness 0.15)
				)
				(justify left bottom)
			)
		)
		(property "Footprint" ""
			(at 100.965 95.25 0)
			(effects
				(font
					(size 1.27 1.27)
					(thickness 0.15)
				)
				(justify left bottom)
				(hide yes)
			)
		)
		(property "Datasheet" ""
			(at 100.965 100.33 0)
			(effects
				(font
					(size 1.27 1.27)
					(thickness 0.15)
				)
				(justify left bottom)
				(hide yes)
			)
		)
		(property "Description" ""
			(at 92.075 87.63 0)
			(effects
				(font
					(size 1.27 1.27)
				)
			)
		)
		(property "Author" "Antmicro"
			(at 100.965 95.25 0)
			(effects
				(font
					(size 1.27 1.27)
					(thickness 0.15)
				)
				(justify left bottom)
				(hide yes)
			)
		)
		(property "License" "Apache-2.0"
			(at 100.965 97.79 0)
			(effects
				(font
					(size 1.27 1.27)
					(thickness 0.15)
				)
				(justify left bottom)
				(hide yes)
			)
		)
		(pin "1"
		)
		(instances
			(project "lpddr4-test-board"
				(path ""
					(reference "#PWR0287")
					(unit 1)
				)
			)
		)
	)
	(symbol
		(lib_id "antmicropower:GND")
		(at 57.15 87.63 0)
		(unit 1)
		(exclude_from_sim no)
		(in_bom yes)
		(on_board yes)
		(dnp no)
		(property "Reference" "#PWR0271"
			(at 66.04 90.17 0)
			(effects
				(font
					(size 1.27 1.27)
					(thickness 0.15)
				)
				(justify left bottom)
				(hide yes)
			)
		)
		(property "Value" "GND"
			(at 55.245 92.075 0)
			(effects
				(font
					(size 1.27 1.27)
					(thickness 0.15)
				)
				(justify left bottom)
			)
		)
		(property "Footprint" ""
			(at 66.04 95.25 0)
			(effects
				(font
					(size 1.27 1.27)
					(thickness 0.15)
				)
				(justify left bottom)
				(hide yes)
			)
		)
		(property "Datasheet" ""
			(at 66.04 100.33 0)
			(effects
				(font
					(size 1.27 1.27)
					(thickness 0.15)
				)
				(justify left bottom)
				(hide yes)
			)
		)
		(property "Description" ""
			(at 57.15 87.63 0)
			(effects
				(font
					(size 1.27 1.27)
				)
			)
		)
		(property "Author" "Antmicro"
			(at 66.04 95.25 0)
			(effects
				(font
					(size 1.27 1.27)
					(thickness 0.15)
				)
				(justify left bottom)
				(hide yes)
			)
		)
		(property "License" "Apache-2.0"
			(at 66.04 97.79 0)
			(effects
				(font
					(size 1.27 1.27)
					(thickness 0.15)
				)
				(justify left bottom)
				(hide yes)
			)
		)
		(pin "1"
		)
		(instances
			(project "lpddr4-test-board"
				(path ""
					(reference "#PWR0271")
					(unit 1)
				)
			)
		)
	)
	(symbol
		(lib_id "antmicropower:GND")
		(at 85.09 87.63 0)
		(unit 1)
		(exclude_from_sim no)
		(in_bom yes)
		(on_board yes)
		(dnp no)
		(property "Reference" "#PWR0268"
			(at 93.98 90.17 0)
			(effects
				(font
					(size 1.27 1.27)
					(thickness 0.15)
				)
				(justify left bottom)
				(hide yes)
			)
		)
		(property "Value" "GND"
			(at 83.185 92.075 0)
			(effects
				(font
					(size 1.27 1.27)
					(thickness 0.15)
				)
				(justify left bottom)
			)
		)
		(property "Footprint" ""
			(at 93.98 95.25 0)
			(effects
				(font
					(size 1.27 1.27)
					(thickness 0.15)
				)
				(justify left bottom)
				(hide yes)
			)
		)
		(property "Datasheet" ""
			(at 93.98 100.33 0)
			(effects
				(font
					(size 1.27 1.27)
					(thickness 0.15)
				)
				(justify left bottom)
				(hide yes)
			)
		)
		(property "Description" ""
			(at 85.09 87.63 0)
			(effects
				(font
					(size 1.27 1.27)
				)
			)
		)
		(property "Author" "Antmicro"
			(at 93.98 95.25 0)
			(effects
				(font
					(size 1.27 1.27)
					(thickness 0.15)
				)
				(justify left bottom)
				(hide yes)
			)
		)
		(property "License" "Apache-2.0"
			(at 93.98 97.79 0)
			(effects
				(font
					(size 1.27 1.27)
					(thickness 0.15)
				)
				(justify left bottom)
				(hide yes)
			)
		)
		(pin "1"
		)
		(instances
			(project "lpddr4-test-board"
				(path ""
					(reference "#PWR0268")
					(unit 1)
				)
			)
		)
	)
	(symbol
		(lib_id "antmicropower:GND")
		(at 50.165 87.63 0)
		(unit 1)
		(exclude_from_sim no)
		(in_bom yes)
		(on_board yes)
		(dnp no)
		(property "Reference" "#PWR0266"
			(at 59.055 90.17 0)
			(effects
				(font
					(size 1.27 1.27)
					(thickness 0.15)
				)
				(justify left bottom)
				(hide yes)
			)
		)
		(property "Value" "GND"
			(at 48.26 92.075 0)
			(effects
				(font
					(size 1.27 1.27)
					(thickness 0.15)
				)
				(justify left bottom)
			)
		)
		(property "Footprint" ""
			(at 59.055 95.25 0)
			(effects
				(font
					(size 1.27 1.27)
					(thickness 0.15)
				)
				(justify left bottom)
				(hide yes)
			)
		)
		(property "Datasheet" ""
			(at 59.055 100.33 0)
			(effects
				(font
					(size 1.27 1.27)
					(thickness 0.15)
				)
				(justify left bottom)
				(hide yes)
			)
		)
		(property "Description" ""
			(at 50.165 87.63 0)
			(effects
				(font
					(size 1.27 1.27)
				)
			)
		)
		(property "Author" "Antmicro"
			(at 59.055 95.25 0)
			(effects
				(font
					(size 1.27 1.27)
					(thickness 0.15)
				)
				(justify left bottom)
				(hide yes)
			)
		)
		(property "License" "Apache-2.0"
			(at 59.055 97.79 0)
			(effects
				(font
					(size 1.27 1.27)
					(thickness 0.15)
				)
				(justify left bottom)
				(hide yes)
			)
		)
		(pin "1"
		)
		(instances
			(project "lpddr4-test-board"
				(path ""
					(reference "#PWR0266")
					(unit 1)
				)
			)
		)
	)
	(symbol
		(lib_id "antmicropower:GND")
		(at 160.655 116.84 0)
		(unit 1)
		(exclude_from_sim no)
		(in_bom yes)
		(on_board yes)
		(dnp no)
		(property "Reference" "#PWR0265"
			(at 169.545 119.38 0)
			(effects
				(font
					(size 1.27 1.27)
					(thickness 0.15)
				)
				(justify left bottom)
				(hide yes)
			)
		)
		(property "Value" "GND"
			(at 158.75 121.285 0)
			(effects
				(font
					(size 1.27 1.27)
					(thickness 0.15)
				)
				(justify left bottom)
			)
		)
		(property "Footprint" ""
			(at 169.545 124.46 0)
			(effects
				(font
					(size 1.27 1.27)
					(thickness 0.15)
				)
				(justify left bottom)
				(hide yes)
			)
		)
		(property "Datasheet" ""
			(at 169.545 129.54 0)
			(effects
				(font
					(size 1.27 1.27)
					(thickness 0.15)
				)
				(justify left bottom)
				(hide yes)
			)
		)
		(property "Description" ""
			(at 160.655 116.84 0)
			(effects
				(font
					(size 1.27 1.27)
				)
			)
		)
		(property "Author" "Antmicro"
			(at 169.545 124.46 0)
			(effects
				(font
					(size 1.27 1.27)
					(thickness 0.15)
				)
				(justify left bottom)
				(hide yes)
			)
		)
		(property "License" "Apache-2.0"
			(at 169.545 127 0)
			(effects
				(font
					(size 1.27 1.27)
					(thickness 0.15)
				)
				(justify left bottom)
				(hide yes)
			)
		)
		(pin "1"
		)
		(instances
			(project "lpddr4-test-board"
				(path ""
					(reference "#PWR0265")
					(unit 1)
				)
			)
		)
	)
	(symbol
		(lib_id "antmicropower:GND")
		(at 63.5 127 0)
		(unit 1)
		(exclude_from_sim no)
		(in_bom yes)
		(on_board yes)
		(dnp no)
		(property "Reference" "#PWR0274"
			(at 72.39 129.54 0)
			(effects
				(font
					(size 1.27 1.27)
					(thickness 0.15)
				)
				(justify left bottom)
				(hide yes)
			)
		)
		(property "Value" "GND"
			(at 61.595 131.445 0)
			(effects
				(font
					(size 1.27 1.27)
					(thickness 0.15)
				)
				(justify left bottom)
			)
		)
		(property "Footprint" ""
			(at 72.39 134.62 0)
			(effects
				(font
					(size 1.27 1.27)
					(thickness 0.15)
				)
				(justify left bottom)
				(hide yes)
			)
		)
		(property "Datasheet" ""
			(at 72.39 139.7 0)
			(effects
				(font
					(size 1.27 1.27)
					(thickness 0.15)
				)
				(justify left bottom)
				(hide yes)
			)
		)
		(property "Description" ""
			(at 63.5 127 0)
			(effects
				(font
					(size 1.27 1.27)
				)
			)
		)
		(property "Author" "Antmicro"
			(at 72.39 134.62 0)
			(effects
				(font
					(size 1.27 1.27)
					(thickness 0.15)
				)
				(justify left bottom)
				(hide yes)
			)
		)
		(property "License" "Apache-2.0"
			(at 72.39 137.16 0)
			(effects
				(font
					(size 1.27 1.27)
					(thickness 0.15)
				)
				(justify left bottom)
				(hide yes)
			)
		)
		(pin "1"
		)
		(instances
			(project "lpddr4-test-board"
				(path ""
					(reference "#PWR0274")
					(unit 1)
				)
			)
		)
	)
	(symbol
		(lib_id "antmicropower:GND")
		(at 77.47 127 0)
		(unit 1)
		(exclude_from_sim no)
		(in_bom yes)
		(on_board yes)
		(dnp no)
		(property "Reference" "#PWR0289"
			(at 86.36 129.54 0)
			(effects
				(font
					(size 1.27 1.27)
					(thickness 0.15)
				)
				(justify left bottom)
				(hide yes)
			)
		)
		(property "Value" "GND"
			(at 75.565 131.445 0)
			(effects
				(font
					(size 1.27 1.27)
					(thickness 0.15)
				)
				(justify left bottom)
			)
		)
		(property "Footprint" ""
			(at 86.36 134.62 0)
			(effects
				(font
					(size 1.27 1.27)
					(thickness 0.15)
				)
				(justify left bottom)
				(hide yes)
			)
		)
		(property "Datasheet" ""
			(at 86.36 139.7 0)
			(effects
				(font
					(size 1.27 1.27)
					(thickness 0.15)
				)
				(justify left bottom)
				(hide yes)
			)
		)
		(property "Description" ""
			(at 77.47 127 0)
			(effects
				(font
					(size 1.27 1.27)
				)
			)
		)
		(property "Author" "Antmicro"
			(at 86.36 134.62 0)
			(effects
				(font
					(size 1.27 1.27)
					(thickness 0.15)
				)
				(justify left bottom)
				(hide yes)
			)
		)
		(property "License" "Apache-2.0"
			(at 86.36 137.16 0)
			(effects
				(font
					(size 1.27 1.27)
					(thickness 0.15)
				)
				(justify left bottom)
				(hide yes)
			)
		)
		(pin "1"
		)
		(instances
			(project "lpddr4-test-board"
				(path ""
					(reference "#PWR0289")
					(unit 1)
				)
			)
		)
	)
	(symbol
		(lib_id "antmicropower:GND")
		(at 169.545 116.84 0)
		(unit 1)
		(exclude_from_sim no)
		(in_bom yes)
		(on_board yes)
		(dnp no)
		(property "Reference" "#PWR0264"
			(at 178.435 119.38 0)
			(effects
				(font
					(size 1.27 1.27)
					(thickness 0.15)
				)
				(justify left bottom)
				(hide yes)
			)
		)
		(property "Value" "GND"
			(at 167.64 121.285 0)
			(effects
				(font
					(size 1.27 1.27)
					(thickness 0.15)
				)
				(justify left bottom)
			)
		)
		(property "Footprint" ""
			(at 178.435 124.46 0)
			(effects
				(font
					(size 1.27 1.27)
					(thickness 0.15)
				)
				(justify left bottom)
				(hide yes)
			)
		)
		(property "Datasheet" ""
			(at 178.435 129.54 0)
			(effects
				(font
					(size 1.27 1.27)
					(thickness 0.15)
				)
				(justify left bottom)
				(hide yes)
			)
		)
		(property "Description" ""
			(at 169.545 116.84 0)
			(effects
				(font
					(size 1.27 1.27)
				)
			)
		)
		(property "Author" "Antmicro"
			(at 178.435 124.46 0)
			(effects
				(font
					(size 1.27 1.27)
					(thickness 0.15)
				)
				(justify left bottom)
				(hide yes)
			)
		)
		(property "License" "Apache-2.0"
			(at 178.435 127 0)
			(effects
				(font
					(size 1.27 1.27)
					(thickness 0.15)
				)
				(justify left bottom)
				(hide yes)
			)
		)
		(pin "1"
		)
		(instances
			(project "lpddr4-test-board"
				(path ""
					(reference "#PWR0264")
					(unit 1)
				)
			)
		)
	)
	(symbol
		(lib_id "antmicropower:GND")
		(at 63.5 161.29 0)
		(unit 1)
		(exclude_from_sim no)
		(in_bom yes)
		(on_board yes)
		(dnp no)
		(property "Reference" "#PWR0279"
			(at 72.39 163.83 0)
			(effects
				(font
					(size 1.27 1.27)
					(thickness 0.15)
				)
				(justify left bottom)
				(hide yes)
			)
		)
		(property "Value" "GND"
			(at 61.595 165.735 0)
			(effects
				(font
					(size 1.27 1.27)
					(thickness 0.15)
				)
				(justify left bottom)
			)
		)
		(property "Footprint" ""
			(at 72.39 168.91 0)
			(effects
				(font
					(size 1.27 1.27)
					(thickness 0.15)
				)
				(justify left bottom)
				(hide yes)
			)
		)
		(property "Datasheet" ""
			(at 72.39 173.99 0)
			(effects
				(font
					(size 1.27 1.27)
					(thickness 0.15)
				)
				(justify left bottom)
				(hide yes)
			)
		)
		(property "Description" ""
			(at 63.5 161.29 0)
			(effects
				(font
					(size 1.27 1.27)
				)
			)
		)
		(property "Author" "Antmicro"
			(at 72.39 168.91 0)
			(effects
				(font
					(size 1.27 1.27)
					(thickness 0.15)
				)
				(justify left bottom)
				(hide yes)
			)
		)
		(property "License" "Apache-2.0"
			(at 72.39 171.45 0)
			(effects
				(font
					(size 1.27 1.27)
					(thickness 0.15)
				)
				(justify left bottom)
				(hide yes)
			)
		)
		(pin "1"
		)
		(instances
			(project "lpddr4-test-board"
				(path ""
					(reference "#PWR0279")
					(unit 1)
				)
			)
		)
	)
	(symbol
		(lib_id "antmicropower:GND")
		(at 70.485 161.29 0)
		(unit 1)
		(exclude_from_sim no)
		(in_bom yes)
		(on_board yes)
		(dnp no)
		(property "Reference" "#PWR0276"
			(at 79.375 163.83 0)
			(effects
				(font
					(size 1.27 1.27)
					(thickness 0.15)
				)
				(justify left bottom)
				(hide yes)
			)
		)
		(property "Value" "GND"
			(at 68.58 165.735 0)
			(effects
				(font
					(size 1.27 1.27)
					(thickness 0.15)
				)
				(justify left bottom)
			)
		)
		(property "Footprint" ""
			(at 79.375 168.91 0)
			(effects
				(font
					(size 1.27 1.27)
					(thickness 0.15)
				)
				(justify left bottom)
				(hide yes)
			)
		)
		(property "Datasheet" ""
			(at 79.375 173.99 0)
			(effects
				(font
					(size 1.27 1.27)
					(thickness 0.15)
				)
				(justify left bottom)
				(hide yes)
			)
		)
		(property "Description" ""
			(at 70.485 161.29 0)
			(effects
				(font
					(size 1.27 1.27)
				)
			)
		)
		(property "Author" "Antmicro"
			(at 79.375 168.91 0)
			(effects
				(font
					(size 1.27 1.27)
					(thickness 0.15)
				)
				(justify left bottom)
				(hide yes)
			)
		)
		(property "License" "Apache-2.0"
			(at 79.375 171.45 0)
			(effects
				(font
					(size 1.27 1.27)
					(thickness 0.15)
				)
				(justify left bottom)
				(hide yes)
			)
		)
		(pin "1"
		)
		(instances
			(project "lpddr4-test-board"
				(path ""
					(reference "#PWR0276")
					(unit 1)
				)
			)
		)
	)
	(symbol
		(lib_id "antmicropower:GND")
		(at 69.215 209.55 0)
		(unit 1)
		(exclude_from_sim no)
		(in_bom yes)
		(on_board yes)
		(dnp no)
		(property "Reference" "#PWR0284"
			(at 78.105 212.09 0)
			(effects
				(font
					(size 1.27 1.27)
					(thickness 0.15)
				)
				(justify left bottom)
				(hide yes)
			)
		)
		(property "Value" "GND"
			(at 67.31 213.995 0)
			(effects
				(font
					(size 1.27 1.27)
					(thickness 0.15)
				)
				(justify left bottom)
			)
		)
		(property "Footprint" ""
			(at 78.105 217.17 0)
			(effects
				(font
					(size 1.27 1.27)
					(thickness 0.15)
				)
				(justify left bottom)
				(hide yes)
			)
		)
		(property "Datasheet" ""
			(at 78.105 222.25 0)
			(effects
				(font
					(size 1.27 1.27)
					(thickness 0.15)
				)
				(justify left bottom)
				(hide yes)
			)
		)
		(property "Description" ""
			(at 69.215 209.55 0)
			(effects
				(font
					(size 1.27 1.27)
				)
			)
		)
		(property "Author" "Antmicro"
			(at 78.105 217.17 0)
			(effects
				(font
					(size 1.27 1.27)
					(thickness 0.15)
				)
				(justify left bottom)
				(hide yes)
			)
		)
		(property "License" "Apache-2.0"
			(at 78.105 219.71 0)
			(effects
				(font
					(size 1.27 1.27)
					(thickness 0.15)
				)
				(justify left bottom)
				(hide yes)
			)
		)
		(pin "1"
		)
		(instances
			(project "lpddr4-test-board"
				(path ""
					(reference "#PWR0284")
					(unit 1)
				)
			)
		)
	)
	(symbol
		(lib_id "antmicropower:GND")
		(at 84.455 161.29 0)
		(unit 1)
		(exclude_from_sim no)
		(in_bom yes)
		(on_board yes)
		(dnp no)
		(property "Reference" "#PWR0277"
			(at 93.345 163.83 0)
			(effects
				(font
					(size 1.27 1.27)
					(thickness 0.15)
				)
				(justify left bottom)
				(hide yes)
			)
		)
		(property "Value" "GND"
			(at 82.55 165.735 0)
			(effects
				(font
					(size 1.27 1.27)
					(thickness 0.15)
				)
				(justify left bottom)
			)
		)
		(property "Footprint" ""
			(at 93.345 168.91 0)
			(effects
				(font
					(size 1.27 1.27)
					(thickness 0.15)
				)
				(justify left bottom)
				(hide yes)
			)
		)
		(property "Datasheet" ""
			(at 93.345 173.99 0)
			(effects
				(font
					(size 1.27 1.27)
					(thickness 0.15)
				)
				(justify left bottom)
				(hide yes)
			)
		)
		(property "Description" ""
			(at 84.455 161.29 0)
			(effects
				(font
					(size 1.27 1.27)
				)
			)
		)
		(property "Author" "Antmicro"
			(at 93.345 168.91 0)
			(effects
				(font
					(size 1.27 1.27)
					(thickness 0.15)
				)
				(justify left bottom)
				(hide yes)
			)
		)
		(property "License" "Apache-2.0"
			(at 93.345 171.45 0)
			(effects
				(font
					(size 1.27 1.27)
					(thickness 0.15)
				)
				(justify left bottom)
				(hide yes)
			)
		)
		(pin "1"
		)
		(instances
			(project "lpddr4-test-board"
				(path ""
					(reference "#PWR0277")
					(unit 1)
				)
			)
		)
	)
	(symbol
		(lib_id "antmicropower:GND")
		(at 43.18 87.63 0)
		(unit 1)
		(exclude_from_sim no)
		(in_bom yes)
		(on_board yes)
		(dnp no)
		(property "Reference" "#PWR0267"
			(at 52.07 90.17 0)
			(effects
				(font
					(size 1.27 1.27)
					(thickness 0.15)
				)
				(justify left bottom)
				(hide yes)
			)
		)
		(property "Value" "GND"
			(at 41.275 92.075 0)
			(effects
				(font
					(size 1.27 1.27)
					(thickness 0.15)
				)
				(justify left bottom)
			)
		)
		(property "Footprint" ""
			(at 52.07 95.25 0)
			(effects
				(font
					(size 1.27 1.27)
					(thickness 0.15)
				)
				(justify left bottom)
				(hide yes)
			)
		)
		(property "Datasheet" ""
			(at 52.07 100.33 0)
			(effects
				(font
					(size 1.27 1.27)
					(thickness 0.15)
				)
				(justify left bottom)
				(hide yes)
			)
		)
		(property "Description" ""
			(at 43.18 87.63 0)
			(effects
				(font
					(size 1.27 1.27)
				)
			)
		)
		(property "Author" "Antmicro"
			(at 52.07 95.25 0)
			(effects
				(font
					(size 1.27 1.27)
					(thickness 0.15)
				)
				(justify left bottom)
				(hide yes)
			)
		)
		(property "License" "Apache-2.0"
			(at 52.07 97.79 0)
			(effects
				(font
					(size 1.27 1.27)
					(thickness 0.15)
				)
				(justify left bottom)
				(hide yes)
			)
		)
		(pin "1"
		)
		(instances
			(project "lpddr4-test-board"
				(path ""
					(reference "#PWR0267")
					(unit 1)
				)
			)
		)
	)
	(symbol
		(lib_id "antmicropower:GND")
		(at 65.405 251.46 0)
		(unit 1)
		(exclude_from_sim no)
		(in_bom yes)
		(on_board yes)
		(dnp no)
		(property "Reference" "#PWR0281"
			(at 74.295 254 0)
			(effects
				(font
					(size 1.27 1.27)
					(thickness 0.15)
				)
				(justify left bottom)
				(hide yes)
			)
		)
		(property "Value" "GND"
			(at 63.5 255.905 0)
			(effects
				(font
					(size 1.27 1.27)
					(thickness 0.15)
				)
				(justify left bottom)
			)
		)
		(property "Footprint" ""
			(at 74.295 259.08 0)
			(effects
				(font
					(size 1.27 1.27)
					(thickness 0.15)
				)
				(justify left bottom)
				(hide yes)
			)
		)
		(property "Datasheet" ""
			(at 74.295 264.16 0)
			(effects
				(font
					(size 1.27 1.27)
					(thickness 0.15)
				)
				(justify left bottom)
				(hide yes)
			)
		)
		(property "Description" ""
			(at 65.405 251.46 0)
			(effects
				(font
					(size 1.27 1.27)
				)
			)
		)
		(property "Author" "Antmicro"
			(at 74.295 259.08 0)
			(effects
				(font
					(size 1.27 1.27)
					(thickness 0.15)
				)
				(justify left bottom)
				(hide yes)
			)
		)
		(property "License" "Apache-2.0"
			(at 74.295 261.62 0)
			(effects
				(font
					(size 1.27 1.27)
					(thickness 0.15)
				)
				(justify left bottom)
				(hide yes)
			)
		)
		(pin "1"
		)
		(instances
			(project "lpddr4-test-board"
				(path ""
					(reference "#PWR0281")
					(unit 1)
				)
			)
		)
	)
	(symbol
		(lib_id "antmicroResistors0402:R_2k2_0402")
		(at 360.045 97.79 0)
		(unit 1)
		(exclude_from_sim no)
		(in_bom yes)
		(on_board yes)
		(dnp no)
		(property "Reference" "R90"
			(at 365.125 97.79 0)
			(effects
				(font
					(size 1.27 1.27)
					(thickness 0.15)
				)
				(justify left bottom)
			)
		)
		(property "Value" "R_2k2_0402"
			(at 380.365 110.49 0)
			(effects
				(font
					(size 1.27 1.27)
					(thickness 0.15)
				)
				(justify left bottom)
				(hide yes)
			)
		)
		(property "Footprint" "antmicro-footprints:R_0402_1005Metric"
			(at 380.365 113.03 0)
			(effects
				(font
					(size 1.27 1.27)
					(thickness 0.15)
				)
				(justify left bottom)
				(hide yes)
			)
		)
		(property "Datasheet" "https://www.bourns.com/docs/product-datasheets/cr.pdf"
			(at 380.365 115.57 0)
			(effects
				(font
					(size 1.27 1.27)
					(thickness 0.15)
				)
				(justify left bottom)
				(hide yes)
			)
		)
		(property "Description" ""
			(at 360.045 97.79 0)
			(effects
				(font
					(size 1.27 1.27)
				)
			)
		)
		(property "Manufacturer" "Bourns"
			(at 380.365 120.65 0)
			(effects
				(font
					(size 1.27 1.27)
					(thickness 0.15)
				)
				(justify left bottom)
				(hide yes)
			)
		)
		(property "MPN" "CR0402-FX-2201GLF"
			(at 380.365 118.11 0)
			(effects
				(font
					(size 1.27 1.27)
					(thickness 0.15)
				)
				(justify left bottom)
				(hide yes)
			)
		)
		(property "Val" "2k2"
			(at 356.235 97.79 0)
			(effects
				(font
					(size 1.27 1.27)
					(thickness 0.15)
				)
				(justify left bottom)
			)
		)
		(property "License" "Apache-2.0"
			(at 380.365 123.19 0)
			(effects
				(font
					(size 1.27 1.27)
					(thickness 0.15)
				)
				(justify left bottom)
				(hide yes)
			)
		)
		(property "Author" "Antmicro"
			(at 380.365 125.73 0)
			(effects
				(font
					(size 1.27 1.27)
					(thickness 0.15)
				)
				(justify left bottom)
				(hide yes)
			)
		)
		(property "Tolerance" "1%"
			(at 380.365 107.95 0)
			(effects
				(font
					(size 1.27 1.27)
				)
				(justify left bottom)
				(hide yes)
			)
		)
		(pin "1"
		)
		(pin "2"
		)
		(instances
			(project "lpddr4-test-board"
				(path ""
					(reference "R90")
					(unit 1)
				)
			)
		)
	)
	(symbol
		(lib_id "antmicropower:GND")
		(at 76.2 209.55 0)
		(unit 1)
		(exclude_from_sim no)
		(in_bom yes)
		(on_board yes)
		(dnp no)
		(property "Reference" "#PWR0283"
			(at 85.09 212.09 0)
			(effects
				(font
					(size 1.27 1.27)
					(thickness 0.15)
				)
				(justify left bottom)
				(hide yes)
			)
		)
		(property "Value" "GND"
			(at 74.295 213.995 0)
			(effects
				(font
					(size 1.27 1.27)
					(thickness 0.15)
				)
				(justify left bottom)
			)
		)
		(property "Footprint" ""
			(at 85.09 217.17 0)
			(effects
				(font
					(size 1.27 1.27)
					(thickness 0.15)
				)
				(justify left bottom)
				(hide yes)
			)
		)
		(property "Datasheet" ""
			(at 85.09 222.25 0)
			(effects
				(font
					(size 1.27 1.27)
					(thickness 0.15)
				)
				(justify left bottom)
				(hide yes)
			)
		)
		(property "Description" ""
			(at 76.2 209.55 0)
			(effects
				(font
					(size 1.27 1.27)
				)
			)
		)
		(property "Author" "Antmicro"
			(at 85.09 217.17 0)
			(effects
				(font
					(size 1.27 1.27)
					(thickness 0.15)
				)
				(justify left bottom)
				(hide yes)
			)
		)
		(property "License" "Apache-2.0"
			(at 85.09 219.71 0)
			(effects
				(font
					(size 1.27 1.27)
					(thickness 0.15)
				)
				(justify left bottom)
				(hide yes)
			)
		)
		(pin "1"
		)
		(instances
			(project "lpddr4-test-board"
				(path ""
					(reference "#PWR0283")
					(unit 1)
				)
			)
		)
	)
	(symbol
		(lib_id "antmicropower:GND")
		(at 71.12 87.63 0)
		(unit 1)
		(exclude_from_sim no)
		(in_bom yes)
		(on_board yes)
		(dnp no)
		(property "Reference" "#PWR0270"
			(at 80.01 90.17 0)
			(effects
				(font
					(size 1.27 1.27)
					(thickness 0.15)
				)
				(justify left bottom)
				(hide yes)
			)
		)
		(property "Value" "GND"
			(at 69.215 92.075 0)
			(effects
				(font
					(size 1.27 1.27)
					(thickness 0.15)
				)
				(justify left bottom)
			)
		)
		(property "Footprint" ""
			(at 80.01 95.25 0)
			(effects
				(font
					(size 1.27 1.27)
					(thickness 0.15)
				)
				(justify left bottom)
				(hide yes)
			)
		)
		(property "Datasheet" ""
			(at 80.01 100.33 0)
			(effects
				(font
					(size 1.27 1.27)
					(thickness 0.15)
				)
				(justify left bottom)
				(hide yes)
			)
		)
		(property "Description" ""
			(at 71.12 87.63 0)
			(effects
				(font
					(size 1.27 1.27)
				)
			)
		)
		(property "Author" "Antmicro"
			(at 80.01 95.25 0)
			(effects
				(font
					(size 1.27 1.27)
					(thickness 0.15)
				)
				(justify left bottom)
				(hide yes)
			)
		)
		(property "License" "Apache-2.0"
			(at 80.01 97.79 0)
			(effects
				(font
					(size 1.27 1.27)
					(thickness 0.15)
				)
				(justify left bottom)
				(hide yes)
			)
		)
		(pin "1"
		)
		(instances
			(project "lpddr4-test-board"
				(path ""
					(reference "#PWR0270")
					(unit 1)
				)
			)
		)
	)
	(symbol
		(lib_id "antmicropower:GND")
		(at 79.375 251.46 0)
		(unit 1)
		(exclude_from_sim no)
		(in_bom yes)
		(on_board yes)
		(dnp no)
		(property "Reference" "#PWR0286"
			(at 88.265 254 0)
			(effects
				(font
					(size 1.27 1.27)
					(thickness 0.15)
				)
				(justify left bottom)
				(hide yes)
			)
		)
		(property "Value" "GND"
			(at 77.47 255.905 0)
			(effects
				(font
					(size 1.27 1.27)
					(thickness 0.15)
				)
				(justify left bottom)
			)
		)
		(property "Footprint" ""
			(at 88.265 259.08 0)
			(effects
				(font
					(size 1.27 1.27)
					(thickness 0.15)
				)
				(justify left bottom)
				(hide yes)
			)
		)
		(property "Datasheet" ""
			(at 88.265 264.16 0)
			(effects
				(font
					(size 1.27 1.27)
					(thickness 0.15)
				)
				(justify left bottom)
				(hide yes)
			)
		)
		(property "Description" ""
			(at 79.375 251.46 0)
			(effects
				(font
					(size 1.27 1.27)
				)
			)
		)
		(property "Author" "Antmicro"
			(at 88.265 259.08 0)
			(effects
				(font
					(size 1.27 1.27)
					(thickness 0.15)
				)
				(justify left bottom)
				(hide yes)
			)
		)
		(property "License" "Apache-2.0"
			(at 88.265 261.62 0)
			(effects
				(font
					(size 1.27 1.27)
					(thickness 0.15)
				)
				(justify left bottom)
				(hide yes)
			)
		)
		(pin "1"
		)
		(instances
			(project "lpddr4-test-board"
				(path ""
					(reference "#PWR0286")
					(unit 1)
				)
			)
		)
	)
	(symbol
		(lib_id "antmicropower:GND")
		(at 83.185 209.55 0)
		(unit 1)
		(exclude_from_sim no)
		(in_bom yes)
		(on_board yes)
		(dnp no)
		(property "Reference" "#PWR0282"
			(at 92.075 212.09 0)
			(effects
				(font
					(size 1.27 1.27)
					(thickness 0.15)
				)
				(justify left bottom)
				(hide yes)
			)
		)
		(property "Value" "GND"
			(at 81.28 213.995 0)
			(effects
				(font
					(size 1.27 1.27)
					(thickness 0.15)
				)
				(justify left bottom)
			)
		)
		(property "Footprint" ""
			(at 92.075 217.17 0)
			(effects
				(font
					(size 1.27 1.27)
					(thickness 0.15)
				)
				(justify left bottom)
				(hide yes)
			)
		)
		(property "Datasheet" ""
			(at 92.075 222.25 0)
			(effects
				(font
					(size 1.27 1.27)
					(thickness 0.15)
				)
				(justify left bottom)
				(hide yes)
			)
		)
		(property "Description" ""
			(at 83.185 209.55 0)
			(effects
				(font
					(size 1.27 1.27)
				)
			)
		)
		(property "Author" "Antmicro"
			(at 92.075 217.17 0)
			(effects
				(font
					(size 1.27 1.27)
					(thickness 0.15)
				)
				(justify left bottom)
				(hide yes)
			)
		)
		(property "License" "Apache-2.0"
			(at 92.075 219.71 0)
			(effects
				(font
					(size 1.27 1.27)
					(thickness 0.15)
				)
				(justify left bottom)
				(hide yes)
			)
		)
		(pin "1"
		)
		(instances
			(project "lpddr4-test-board"
				(path ""
					(reference "#PWR0282")
					(unit 1)
				)
			)
		)
	)
)
